FILE_TYPE = MACRO_DRAWING;
SET COLOR_WIRE YELLOW;
SET COLOR_PROP ORANGE;
SET COLOR_DOT WHITE;
SET COLOR_ARC YELLOW;
SET COLOR_BODY GREEN;
SET COLOR_NOTE PURPLE;
SET PROP_DISPLAY VALUE;
SET PAGE_NUMBER P119;
FORCEADD Q_RES..1
(-2100 475);
FORCEPROP 1 LAST PART_NUMBER CS12402FB01
J 0
(-2200 525);
DISPLAY 0.510638 (-2200 525);
DISPLAY INVISIBLE (-2200 525);
FORCEPROP 1 LAST VALUE 240
J 2
(-1900 475);
DISPLAY 0.638298 (-1900 475);
FORCEPROP 1 LAST TOLERANCE 1%
J 0
(-1875 475);
DISPLAY 0.638298 (-1875 475);
FORCEPROP 1 LAST MATERIAL EMPTY
J 0
(-1775 475);
DISPLAY 0.638298 (-1775 475);
PAINT RED (-1775 475);
FORCEPROP 1 LAST $LOCATION R262
J 0
(-2325 475);
DISPLAY 0.787234 (-2325 475);
FORCEPROP 1 LASTPIN (-2200 475) $PN 1
J 0
(-2188 487);
DISPLAY 0.787234 (-2188 487);
FORCEPROP 1 LASTPIN (-2000 475) $PN 2
J 0
(-2038 487);
DISPLAY 0.787234 (-2038 487);
FORCEPROP 1 LAST WATTAGE 1/16W
J 2
(-1925 550);
DISPLAY 0.510638 (-1925 550);
DISPLAY INVISIBLE (-1925 550);
FORCEPROP 1 LAST PACK_TYPE 0402LF
J 0
(-2200 550);
DISPLAY 0.510638 (-2200 550);
DISPLAY INVISIBLE (-2200 550);
FORCEPROP 2 LAST CDS_LIB pure_quanta
J 0
(-2100 475);
PAINT MONO (-2100 475);
DISPLAY INVISIBLE (-2100 475);
FORCEPROP 1 LAST PATH I100
J 0
(-2150 625);
DISPLAY 0.978723 (-2150 625);
PAINT WHITE (-2150 625);
DISPLAY INVISIBLE (-2150 625);
FORCEPROP 2 LAST CDS_LOCATION R262
J 0
(-2150 675);
DISPLAY 1.021277 (-2150 675);
DISPLAY INVISIBLE (-2150 675);
FORCEPROP 2 LAST $SEC 1
J 0
(-2150 675);
DISPLAY 0.680851 (-2150 675);
PAINT MONO (-2150 675);
DISPLAY INVISIBLE (-2150 675);
FORCEPROP 2 LAST CDS_SEC 1
J 0
(-2150 675);
DISPLAY 1.021277 (-2150 675);
DISPLAY INVISIBLE (-2150 675);
FORCEADD Q_RES..1
(-2100 600);
FORCEPROP 1 LAST PART_NUMBER CS12402FB01
J 0
(-2200 650);
DISPLAY 0.510638 (-2200 650);
DISPLAY INVISIBLE (-2200 650);
FORCEPROP 1 LAST VALUE 240
J 2
(-1900 600);
DISPLAY 0.638298 (-1900 600);
FORCEPROP 1 LAST PACK_TYPE 0402LF
J 0
(-2200 675);
DISPLAY 0.510638 (-2200 675);
FORCEPROP 1 LAST WATTAGE 1/16W
J 2
(-1925 675);
DISPLAY 0.510638 (-1925 675);
FORCEPROP 1 LAST MATERIAL EMPTY
J 0
(-1775 600);
DISPLAY 0.638298 (-1775 600);
PAINT RED (-1775 600);
FORCEPROP 1 LAST TOLERANCE 1%
J 0
(-1875 600);
DISPLAY 0.638298 (-1875 600);
FORCEPROP 1 LAST $LOCATION R261
J 0
(-2325 600);
DISPLAY 0.787234 (-2325 600);
FORCEPROP 1 LASTPIN (-2200 600) $PN 1
J 0
(-2188 612);
DISPLAY 0.787234 (-2188 612);
FORCEPROP 1 LASTPIN (-2000 600) $PN 2
J 0
(-2038 612);
DISPLAY 0.787234 (-2038 612);
FORCEPROP 2 LAST CDS_LIB pure_quanta
J 0
(-2100 600);
PAINT MONO (-2100 600);
DISPLAY INVISIBLE (-2100 600);
FORCEPROP 1 LAST PATH I101
J 0
(-2150 750);
DISPLAY 0.978723 (-2150 750);
PAINT WHITE (-2150 750);
DISPLAY INVISIBLE (-2150 750);
FORCEPROP 2 LAST CDS_LOCATION R261
J 0
(-2150 800);
DISPLAY 1.021277 (-2150 800);
DISPLAY INVISIBLE (-2150 800);
FORCEPROP 2 LAST $SEC 1
J 0
(-2150 800);
DISPLAY 0.680851 (-2150 800);
PAINT MONO (-2150 800);
DISPLAY INVISIBLE (-2150 800);
FORCEPROP 2 LAST CDS_SEC 1
J 0
(-2150 800);
DISPLAY 1.021277 (-2150 800);
DISPLAY INVISIBLE (-2150 800);
FORCEADD UNIVERSAL_POWER..1
(-2400 850);
FORCEPROP 3 LASTPIN (-2400 800) SIG_NAME PVNN_TERM_CPU1\g
J 0
(-2390 810);
DISPLAY 0.659574 (-2390 810);
PAINT MONO (-2390 810);
DISPLAY INVISIBLE (-2390 810);
FORCEPROP 1 LAST HDL_POWER PVNN_TERM_CPU1
J 1
(-2400 900);
DISPLAY 0.872340 (-2400 900);
PAINT GREEN (-2400 900);
FORCEPROP 2 LAST CDS_LIB logical_power
J 0
(-2400 850);
DISPLAY INVISIBLE (-2400 850);
FORCEPROP 1 LAST PATH I102
J 0
(-2350 875);
DISPLAY 0.872340 (-2350 875);
PAINT AQUA (-2350 875);
DISPLAY INVISIBLE (-2350 875);
FORCEADD OFFPAGE..1
R 2
(1525 -1275);
FORCEPROP 2 LAST $XR1 214 
J 0
(1801 -1275);
DISPLAY 0.638298 (1801 -1275);
PAINT MONO (1801 -1275);
FORCEPROP 2 LAST $XR0 44 
J 0
(1711 -1275);
DISPLAY 0.638298 (1711 -1275);
PAINT MONO (1711 -1275);
FORCEPROP 2 LAST CDS_LIB standard
J 0
(1525 -1275);
PAINT MONO (1525 -1275);
DISPLAY INVISIBLE (1525 -1275);
FORCEPROP 1 LAST OFFPAGE TRUE
J 2
(1200 -1400);
DISPLAY 0.872340 (1200 -1400);
DISPLAY INVISIBLE (1200 -1400);
FORCEPROP 1 LAST COMMENT_BODY TRUE
J 2
(1400 -1375);
DISPLAY 0.872340 (1400 -1375);
PAINT GREEN (1400 -1375);
DISPLAY INVISIBLE (1400 -1375);
FORCEPROP 2 LAST PATH I103
J 0
(1700 -1200);
DISPLAY 1.021277 (1700 -1200);
DISPLAY INVISIBLE (1700 -1200);
FORCEADD OFFPAGE..1
R 2
(1525 -1025);
FORCEPROP 2 LAST $XR1 214 
J 0
(1801 -1025);
DISPLAY 0.638298 (1801 -1025);
PAINT MONO (1801 -1025);
FORCEPROP 2 LAST $XR0 44 
J 0
(1711 -1025);
DISPLAY 0.638298 (1711 -1025);
PAINT MONO (1711 -1025);
FORCEPROP 2 LAST CDS_LIB standard
J 0
(1525 -1025);
PAINT MONO (1525 -1025);
DISPLAY INVISIBLE (1525 -1025);
FORCEPROP 1 LAST OFFPAGE TRUE
J 2
(1200 -1150);
DISPLAY 0.872340 (1200 -1150);
DISPLAY INVISIBLE (1200 -1150);
FORCEPROP 1 LAST COMMENT_BODY TRUE
J 2
(1400 -1125);
DISPLAY 0.872340 (1400 -1125);
PAINT GREEN (1400 -1125);
DISPLAY INVISIBLE (1400 -1125);
FORCEPROP 2 LAST PATH I104
J 0
(1700 -950);
DISPLAY 1.021277 (1700 -950);
DISPLAY INVISIBLE (1700 -950);
FORCEADD OFFPAGE..1
R 2
(1525 -900);
FORCEPROP 2 LAST $XR1 214 
J 0
(1801 -900);
DISPLAY 0.638298 (1801 -900);
PAINT MONO (1801 -900);
FORCEPROP 2 LAST $XR0 44 
J 0
(1711 -900);
DISPLAY 0.638298 (1711 -900);
PAINT MONO (1711 -900);
FORCEPROP 2 LAST CDS_LIB standard
J 0
(1525 -900);
PAINT MONO (1525 -900);
DISPLAY INVISIBLE (1525 -900);
FORCEPROP 1 LAST OFFPAGE TRUE
J 2
(1200 -1025);
DISPLAY 0.872340 (1200 -1025);
DISPLAY INVISIBLE (1200 -1025);
FORCEPROP 1 LAST COMMENT_BODY TRUE
J 2
(1400 -1000);
DISPLAY 0.872340 (1400 -1000);
PAINT GREEN (1400 -1000);
DISPLAY INVISIBLE (1400 -1000);
FORCEPROP 2 LAST PATH I105
J 0
(1700 -825);
DISPLAY 1.021277 (1700 -825);
DISPLAY INVISIBLE (1700 -825);
FORCEADD OFFPAGE..1
R 2
(1525 -775);
FORCEPROP 2 LAST $XR1 214 
J 0
(1801 -775);
DISPLAY 0.638298 (1801 -775);
PAINT MONO (1801 -775);
FORCEPROP 2 LAST $XR0 44 
J 0
(1711 -775);
DISPLAY 0.638298 (1711 -775);
PAINT MONO (1711 -775);
FORCEPROP 2 LAST CDS_LIB standard
J 0
(1525 -775);
PAINT MONO (1525 -775);
DISPLAY INVISIBLE (1525 -775);
FORCEPROP 1 LAST OFFPAGE TRUE
J 2
(1200 -900);
DISPLAY 0.872340 (1200 -900);
DISPLAY INVISIBLE (1200 -900);
FORCEPROP 1 LAST COMMENT_BODY TRUE
J 2
(1400 -875);
DISPLAY 0.872340 (1400 -875);
PAINT GREEN (1400 -875);
DISPLAY INVISIBLE (1400 -875);
FORCEPROP 2 LAST PATH I106
J 0
(1700 -700);
DISPLAY 1.021277 (1700 -700);
DISPLAY INVISIBLE (1700 -700);
FORCEADD OFFPAGE..2
(-750 -275);
FORCEPROP 2 LAST $XR0 44 
J 0
(-561 -275);
DISPLAY 0.638298 (-561 -275);
PAINT MONO (-561 -275);
FORCEPROP 2 LAST CDS_LIB standard
J 0
(-750 -275);
DISPLAY INVISIBLE (-750 -275);
FORCEPROP 1 LAST OFFPAGE TRUE
J 0
(-425 -400);
DISPLAY 0.872340 (-425 -400);
PAINT GREEN (-425 -400);
DISPLAY INVISIBLE (-425 -400);
FORCEPROP 1 LAST COMMENT_BODY TRUE
J 0
(-795 -370);
DISPLAY 0.872340 (-795 -370);
PAINT GREEN (-795 -370);
DISPLAY INVISIBLE (-795 -370);
FORCEPROP 2 LAST PATH I107
J 0
(-550 -225);
DISPLAY 1.021277 (-550 -225);
DISPLAY INVISIBLE (-550 -225);
FORCEADD OFFPAGE..2
(-750 -150);
FORCEPROP 2 LAST $XR0 44 
J 0
(-561 -150);
DISPLAY 0.638298 (-561 -150);
PAINT MONO (-561 -150);
FORCEPROP 2 LAST CDS_LIB standard
J 0
(-750 -150);
DISPLAY INVISIBLE (-750 -150);
FORCEPROP 1 LAST OFFPAGE TRUE
J 0
(-425 -275);
DISPLAY 0.872340 (-425 -275);
PAINT GREEN (-425 -275);
DISPLAY INVISIBLE (-425 -275);
FORCEPROP 1 LAST COMMENT_BODY TRUE
J 0
(-795 -245);
DISPLAY 0.872340 (-795 -245);
PAINT GREEN (-795 -245);
DISPLAY INVISIBLE (-795 -245);
FORCEPROP 2 LAST PATH I108
J 0
(-550 -100);
DISPLAY 1.021277 (-550 -100);
DISPLAY INVISIBLE (-550 -100);
FORCEADD OFFPAGE..2
(-750 -25);
FORCEPROP 2 LAST $XR0 44 
J 0
(-561 -25);
DISPLAY 0.638298 (-561 -25);
PAINT MONO (-561 -25);
FORCEPROP 2 LAST CDS_LIB standard
J 0
(-750 -25);
DISPLAY INVISIBLE (-750 -25);
FORCEPROP 1 LAST OFFPAGE TRUE
J 0
(-425 -150);
DISPLAY 0.872340 (-425 -150);
PAINT GREEN (-425 -150);
DISPLAY INVISIBLE (-425 -150);
FORCEPROP 1 LAST COMMENT_BODY TRUE
J 0
(-795 -120);
DISPLAY 0.872340 (-795 -120);
PAINT GREEN (-795 -120);
DISPLAY INVISIBLE (-795 -120);
FORCEPROP 2 LAST PATH I109
J 0
(-550 25);
DISPLAY 1.021277 (-550 25);
DISPLAY INVISIBLE (-550 25);
FORCEADD OFFPAGE..2
(-750 100);
FORCEPROP 2 LAST $XR0 44 
J 0
(-561 100);
DISPLAY 0.638298 (-561 100);
PAINT MONO (-561 100);
FORCEPROP 2 LAST CDS_LIB standard
J 0
(-750 100);
DISPLAY INVISIBLE (-750 100);
FORCEPROP 1 LAST OFFPAGE TRUE
J 0
(-425 -25);
DISPLAY 0.872340 (-425 -25);
PAINT GREEN (-425 -25);
DISPLAY INVISIBLE (-425 -25);
FORCEPROP 1 LAST COMMENT_BODY TRUE
J 0
(-795 5);
DISPLAY 0.872340 (-795 5);
PAINT GREEN (-795 5);
DISPLAY INVISIBLE (-795 5);
FORCEPROP 2 LAST PATH I110
J 0
(-550 150);
DISPLAY 1.021277 (-550 150);
DISPLAY INVISIBLE (-550 150);
FORCEADD OFFPAGE..2
(-750 225);
FORCEPROP 2 LAST $XR0 44 
J 0
(-561 225);
DISPLAY 0.638298 (-561 225);
PAINT MONO (-561 225);
FORCEPROP 2 LAST CDS_LIB standard
J 0
(-750 225);
DISPLAY INVISIBLE (-750 225);
FORCEPROP 1 LAST OFFPAGE TRUE
J 0
(-425 100);
DISPLAY 0.872340 (-425 100);
PAINT GREEN (-425 100);
DISPLAY INVISIBLE (-425 100);
FORCEPROP 1 LAST COMMENT_BODY TRUE
J 0
(-795 130);
DISPLAY 0.872340 (-795 130);
PAINT GREEN (-795 130);
DISPLAY INVISIBLE (-795 130);
FORCEPROP 2 LAST PATH I111
J 0
(-550 275);
DISPLAY 1.021277 (-550 275);
DISPLAY INVISIBLE (-550 275);
FORCEADD OFFPAGE..2
(-750 350);
FORCEPROP 2 LAST $XR0 44 
J 0
(-561 350);
DISPLAY 0.638298 (-561 350);
PAINT MONO (-561 350);
FORCEPROP 2 LAST CDS_LIB standard
J 0
(-750 350);
DISPLAY INVISIBLE (-750 350);
FORCEPROP 1 LAST OFFPAGE TRUE
J 0
(-425 225);
DISPLAY 0.872340 (-425 225);
PAINT GREEN (-425 225);
DISPLAY INVISIBLE (-425 225);
FORCEPROP 1 LAST COMMENT_BODY TRUE
J 0
(-795 255);
DISPLAY 0.872340 (-795 255);
PAINT GREEN (-795 255);
DISPLAY INVISIBLE (-795 255);
FORCEPROP 2 LAST PATH I112
J 0
(-550 400);
DISPLAY 1.021277 (-550 400);
DISPLAY INVISIBLE (-550 400);
FORCEADD OFFPAGE..2
(-750 475);
FORCEPROP 2 LAST $XR0 44 
J 0
(-561 475);
DISPLAY 0.638298 (-561 475);
PAINT MONO (-561 475);
FORCEPROP 2 LAST CDS_LIB standard
J 0
(-750 475);
DISPLAY INVISIBLE (-750 475);
FORCEPROP 1 LAST OFFPAGE TRUE
J 0
(-425 350);
DISPLAY 0.872340 (-425 350);
PAINT GREEN (-425 350);
DISPLAY INVISIBLE (-425 350);
FORCEPROP 1 LAST COMMENT_BODY TRUE
J 0
(-795 380);
DISPLAY 0.872340 (-795 380);
PAINT GREEN (-795 380);
DISPLAY INVISIBLE (-795 380);
FORCEPROP 2 LAST PATH I113
J 0
(-550 525);
DISPLAY 1.021277 (-550 525);
DISPLAY INVISIBLE (-550 525);
FORCEADD OFFPAGE..2
(-750 600);
FORCEPROP 2 LAST $XR0 44 
J 0
(-561 600);
DISPLAY 0.638298 (-561 600);
PAINT MONO (-561 600);
FORCEPROP 2 LAST CDS_LIB standard
J 0
(-750 600);
DISPLAY INVISIBLE (-750 600);
FORCEPROP 1 LAST OFFPAGE TRUE
J 0
(-425 475);
DISPLAY 0.872340 (-425 475);
PAINT GREEN (-425 475);
DISPLAY INVISIBLE (-425 475);
FORCEPROP 1 LAST COMMENT_BODY TRUE
J 0
(-795 505);
DISPLAY 0.872340 (-795 505);
PAINT GREEN (-795 505);
DISPLAY INVISIBLE (-795 505);
FORCEPROP 2 LAST PATH I114
J 0
(-550 650);
DISPLAY 1.021277 (-550 650);
DISPLAY INVISIBLE (-550 650);
FORCEADD Q_RES..1
(250 250);
FORCEPROP 1 LAST PART_NUMBER CS12402FB01
J 0
(150 300);
DISPLAY 0.510638 (150 300);
DISPLAY INVISIBLE (150 300);
FORCEPROP 1 LAST VALUE 240
J 2
(450 250);
DISPLAY 0.638298 (450 250);
FORCEPROP 1 LAST TOLERANCE 1%
J 0
(475 250);
DISPLAY 0.638298 (475 250);
FORCEPROP 1 LAST MATERIAL EMPTY
J 0
(575 250);
DISPLAY 0.638298 (575 250);
PAINT RED (575 250);
FORCEPROP 1 LAST $LOCATION R291
J 0
(25 250);
DISPLAY 0.787234 (25 250);
FORCEPROP 1 LASTPIN (150 250) $PN 1
J 0
(162 262);
DISPLAY 0.787234 (162 262);
FORCEPROP 1 LASTPIN (350 250) $PN 2
J 0
(312 262);
DISPLAY 0.787234 (312 262);
FORCEPROP 2 LAST CDS_LIB pure_quanta
J 0
(250 250);
PAINT MONO (250 250);
DISPLAY INVISIBLE (250 250);
FORCEPROP 1 LAST PACK_TYPE 0402LF
J 0
(150 325);
DISPLAY 0.510638 (150 325);
DISPLAY INVISIBLE (150 325);
FORCEPROP 1 LAST WATTAGE 1/16W
J 2
(425 325);
DISPLAY 0.510638 (425 325);
DISPLAY INVISIBLE (425 325);
FORCEPROP 1 LAST PATH I116
J 0
(200 400);
DISPLAY 0.978723 (200 400);
PAINT WHITE (200 400);
DISPLAY INVISIBLE (200 400);
FORCEPROP 2 LAST CDS_LOCATION R291
J 0
(200 450);
DISPLAY 1.021277 (200 450);
DISPLAY INVISIBLE (200 450);
FORCEPROP 2 LAST $SEC 1
J 0
(200 450);
DISPLAY 0.680851 (200 450);
PAINT MONO (200 450);
DISPLAY INVISIBLE (200 450);
FORCEPROP 2 LAST CDS_SEC 1
J 0
(200 450);
DISPLAY 1.021277 (200 450);
DISPLAY INVISIBLE (200 450);
FORCEADD OFFPAGE..2
(1650 250);
FORCEPROP 2 LAST $XR0 45 
J 0
(1839 250);
DISPLAY 0.638298 (1839 250);
PAINT MONO (1839 250);
FORCEPROP 2 LAST CDS_LIB standard
J 0
(1650 250);
DISPLAY INVISIBLE (1650 250);
FORCEPROP 1 LAST OFFPAGE TRUE
J 0
(1975 125);
DISPLAY 0.872340 (1975 125);
PAINT GREEN (1975 125);
DISPLAY INVISIBLE (1975 125);
FORCEPROP 1 LAST COMMENT_BODY TRUE
J 0
(1605 155);
DISPLAY 0.872340 (1605 155);
PAINT GREEN (1605 155);
DISPLAY INVISIBLE (1605 155);
FORCEPROP 2 LAST PATH I120
J 0
(1850 300);
DISPLAY 1.021277 (1850 300);
DISPLAY INVISIBLE (1850 300);
FORCEADD OFFPAGE..2
(1650 375);
FORCEPROP 2 LAST $XR0 44 
J 0
(1839 375);
DISPLAY 0.638298 (1839 375);
PAINT MONO (1839 375);
FORCEPROP 2 LAST CDS_LIB standard
J 0
(1650 375);
DISPLAY INVISIBLE (1650 375);
FORCEPROP 1 LAST OFFPAGE TRUE
J 0
(1975 250);
DISPLAY 0.872340 (1975 250);
PAINT GREEN (1975 250);
DISPLAY INVISIBLE (1975 250);
FORCEPROP 1 LAST COMMENT_BODY TRUE
J 0
(1605 280);
DISPLAY 0.872340 (1605 280);
PAINT GREEN (1605 280);
DISPLAY INVISIBLE (1605 280);
FORCEPROP 2 LAST PATH I121
J 0
(1850 425);
DISPLAY 1.021277 (1850 425);
DISPLAY INVISIBLE (1850 425);
FORCEADD OFFPAGE..1
R 2
(1525 -1150);
FORCEPROP 2 LAST $XR1 214 
J 0
(1801 -1150);
DISPLAY 0.638298 (1801 -1150);
PAINT MONO (1801 -1150);
FORCEPROP 2 LAST $XR0 44 
J 0
(1711 -1150);
DISPLAY 0.638298 (1711 -1150);
PAINT MONO (1711 -1150);
FORCEPROP 2 LAST CDS_LIB standard
J 0
(1525 -1150);
PAINT MONO (1525 -1150);
DISPLAY INVISIBLE (1525 -1150);
FORCEPROP 1 LAST OFFPAGE TRUE
J 2
(1200 -1275);
DISPLAY 0.872340 (1200 -1275);
DISPLAY INVISIBLE (1200 -1275);
FORCEPROP 1 LAST COMMENT_BODY TRUE
J 2
(1400 -1250);
DISPLAY 0.872340 (1400 -1250);
PAINT GREEN (1400 -1250);
DISPLAY INVISIBLE (1400 -1250);
FORCEPROP 2 LAST PATH I124
J 0
(1700 -1075);
DISPLAY 1.021277 (1700 -1075);
DISPLAY INVISIBLE (1700 -1075);
FORCEADD Q_RES..1
(-2100 350);
FORCEPROP 1 LAST PART_NUMBER CS12402FB01
J 0
(-2200 400);
DISPLAY 0.510638 (-2200 400);
DISPLAY INVISIBLE (-2200 400);
FORCEPROP 1 LAST VALUE 240
J 2
(-1900 350);
DISPLAY 0.638298 (-1900 350);
FORCEPROP 1 LAST MATERIAL EMPTY
J 0
(-1775 350);
DISPLAY 0.638298 (-1775 350);
PAINT RED (-1775 350);
FORCEPROP 1 LAST TOLERANCE 1%
J 0
(-1875 350);
DISPLAY 0.638298 (-1875 350);
FORCEPROP 1 LAST $LOCATION R263
J 0
(-2325 350);
DISPLAY 0.787234 (-2325 350);
FORCEPROP 1 LASTPIN (-2200 350) $PN 1
J 0
(-2188 362);
DISPLAY 0.787234 (-2188 362);
FORCEPROP 1 LASTPIN (-2000 350) $PN 2
J 0
(-2038 362);
DISPLAY 0.787234 (-2038 362);
FORCEPROP 1 LAST PACK_TYPE 0402LF
J 0
(-2200 425);
DISPLAY 0.510638 (-2200 425);
DISPLAY INVISIBLE (-2200 425);
FORCEPROP 1 LAST WATTAGE 1/16W
J 2
(-1925 425);
DISPLAY 0.510638 (-1925 425);
DISPLAY INVISIBLE (-1925 425);
FORCEPROP 2 LAST CDS_LIB pure_quanta
J 0
(-2100 350);
PAINT MONO (-2100 350);
DISPLAY INVISIBLE (-2100 350);
FORCEPROP 1 LAST PATH I125
J 0
(-2150 500);
DISPLAY 0.978723 (-2150 500);
PAINT WHITE (-2150 500);
DISPLAY INVISIBLE (-2150 500);
FORCEPROP 2 LAST CDS_LOCATION R263
J 0
(-2150 550);
DISPLAY 1.021277 (-2150 550);
DISPLAY INVISIBLE (-2150 550);
FORCEPROP 2 LAST $SEC 1
J 0
(-2150 550);
DISPLAY 0.680851 (-2150 550);
PAINT MONO (-2150 550);
DISPLAY INVISIBLE (-2150 550);
FORCEPROP 2 LAST CDS_SEC 1
J 0
(-2150 550);
DISPLAY 1.021277 (-2150 550);
DISPLAY INVISIBLE (-2150 550);
FORCEADD Q_RES..1
(250 375);
FORCEPROP 1 LAST PART_NUMBER CS12402FB01
J 0
(150 425);
DISPLAY 0.510638 (150 425);
DISPLAY INVISIBLE (150 425);
FORCEPROP 1 LAST VALUE 240
J 2
(450 375);
DISPLAY 0.638298 (450 375);
FORCEPROP 1 LAST TOLERANCE 1%
J 0
(475 375);
DISPLAY 0.638298 (475 375);
FORCEPROP 1 LAST MATERIAL CHIP
J 0
(575 375);
DISPLAY 0.638298 (575 375);
FORCEPROP 1 LAST $LOCATION R290
J 0
(25 375);
DISPLAY 0.787234 (25 375);
FORCEPROP 1 LASTPIN (150 375) $PN 1
J 0
(162 387);
DISPLAY 0.787234 (162 387);
FORCEPROP 1 LASTPIN (350 375) $PN 2
J 0
(312 387);
DISPLAY 0.787234 (312 387);
FORCEPROP 2 LAST CDS_LIB pure_quanta
J 0
(250 375);
PAINT MONO (250 375);
DISPLAY INVISIBLE (250 375);
FORCEPROP 1 LAST WATTAGE 1/16W
J 2
(450 450);
DISPLAY 0.510638 (450 450);
DISPLAY INVISIBLE (450 450);
FORCEPROP 1 LAST PACK_TYPE 0402LF
J 0
(150 450);
DISPLAY 0.510638 (150 450);
DISPLAY INVISIBLE (150 450);
FORCEPROP 1 LAST PATH I135
J 0
(200 525);
DISPLAY 0.978723 (200 525);
PAINT WHITE (200 525);
DISPLAY INVISIBLE (200 525);
FORCEPROP 2 LAST CDS_LOCATION R290
J 0
(200 575);
DISPLAY 1.021277 (200 575);
DISPLAY INVISIBLE (200 575);
FORCEPROP 2 LAST $SEC 1
J 0
(200 575);
DISPLAY 0.680851 (200 575);
PAINT MONO (200 575);
DISPLAY INVISIBLE (200 575);
FORCEPROP 2 LAST CDS_SEC 1
J 0
(200 575);
DISPLAY 1.021277 (200 575);
DISPLAY INVISIBLE (200 575);
FORCEADD Q_RES..1
(-2075 1925);
FORCEPROP 1 LAST PART_NUMBER CS21002FB06
J 0
(-2150 2000);
DISPLAY 0.510638 (-2150 2000);
DISPLAY INVISIBLE (-2150 2000);
FORCEPROP 1 LAST WATTAGE 1/16W
J 2
(-1800 2050);
DISPLAY 0.510638 (-1800 2050);
FORCEPROP 1 LAST PACK_TYPE 0402LF
J 0
(-2150 2050);
DISPLAY 0.510638 (-2150 2050);
FORCEPROP 1 LAST MATERIAL EMPTY
J 0
(-1750 1925);
DISPLAY 0.638298 (-1750 1925);
PAINT RED (-1750 1925);
FORCEPROP 1 LAST TOLERANCE 1%
J 0
(-1875 1925);
DISPLAY 0.638298 (-1875 1925);
FORCEPROP 1 LAST VALUE 1K
J 2
(-1900 1925);
DISPLAY 0.638298 (-1900 1925);
FORCEPROP 1 LAST $LOCATION R1009
J 0
(-2325 1925);
DISPLAY 0.808511 (-2325 1925);
FORCEPROP 1 LASTPIN (-2175 1925) $PN 1
J 0
(-2163 1937);
DISPLAY 0.787234 (-2163 1937);
FORCEPROP 1 LASTPIN (-1975 1925) $PN 2
J 0
(-2013 1937);
DISPLAY 0.787234 (-2013 1937);
FORCEPROP 2 LAST CDS_LIB pure_quanta
J 0
(-2075 1925);
PAINT MONO (-2075 1925);
DISPLAY INVISIBLE (-2075 1925);
FORCEPROP 1 LAST PATH I136
J 0
(-2125 2075);
DISPLAY 0.978723 (-2125 2075);
PAINT WHITE (-2125 2075);
DISPLAY INVISIBLE (-2125 2075);
FORCEPROP 2 LAST CDS_LOCATION R1009
J 0
(-2125 2125);
DISPLAY 1.021277 (-2125 2125);
DISPLAY INVISIBLE (-2125 2125);
FORCEPROP 2 LAST $SEC 1
J 0
(-2125 2125);
DISPLAY 0.680851 (-2125 2125);
PAINT MONO (-2125 2125);
DISPLAY INVISIBLE (-2125 2125);
FORCEPROP 2 LAST CDS_SEC 1
J 0
(-2125 2125);
DISPLAY 1.021277 (-2125 2125);
DISPLAY INVISIBLE (-2125 2125);
FORCEADD OFFPAGE..2
(-700 1925);
FORCEPROP 2 LAST $XR0 14 
J 0
(-511 1925);
DISPLAY 0.638298 (-511 1925);
PAINT MONO (-511 1925);
FORCEPROP 2 LAST CDS_LIB standard
J 0
(-700 1925);
PAINT MONO (-700 1925);
DISPLAY INVISIBLE (-700 1925);
FORCEPROP 1 LAST OFFPAGE TRUE
J 0
(-375 1800);
DISPLAY 0.872340 (-375 1800);
PAINT GREEN (-375 1800);
DISPLAY INVISIBLE (-375 1800);
FORCEPROP 1 LAST COMMENT_BODY TRUE
J 0
(-745 1830);
DISPLAY 0.872340 (-745 1830);
PAINT GREEN (-745 1830);
DISPLAY INVISIBLE (-745 1830);
FORCEPROP 2 LAST PATH I137
J 0
(-500 1975);
DISPLAY 1.021277 (-500 1975);
DISPLAY INVISIBLE (-500 1975);
FORCEADD UNIVERSAL_POWER..1
(-2375 2150);
FORCEPROP 3 LASTPIN (-2375 2100) SIG_NAME PVNN_TERM_CPU0\g
J 0
(-2365 2110);
DISPLAY 0.659574 (-2365 2110);
PAINT MONO (-2365 2110);
DISPLAY INVISIBLE (-2365 2110);
FORCEPROP 1 LAST HDL_POWER PVNN_TERM_CPU0
J 1
(-2375 2200);
DISPLAY 0.872340 (-2375 2200);
PAINT GREEN (-2375 2200);
FORCEPROP 2 LAST CDS_LIB logical_power
J 0
(-2375 2150);
PAINT MONO (-2375 2150);
DISPLAY INVISIBLE (-2375 2150);
FORCEPROP 1 LAST PATH I138
J 0
(-2325 2175);
DISPLAY 0.872340 (-2325 2175);
PAINT AQUA (-2325 2175);
DISPLAY INVISIBLE (-2325 2175);
FORCEADD Q_RES..1
(-2100 -1225);
FORCEPROP 1 LAST PART_NUMBER CS21002FB06
J 0
(-2175 -1150);
DISPLAY 0.510638 (-2175 -1150);
DISPLAY INVISIBLE (-2175 -1150);
FORCEPROP 1 LAST MATERIAL EMPTY
J 0
(-1775 -1225);
DISPLAY 0.638298 (-1775 -1225);
PAINT RED (-1775 -1225);
FORCEPROP 1 LAST TOLERANCE 1%
J 0
(-1900 -1225);
DISPLAY 0.638298 (-1900 -1225);
FORCEPROP 1 LAST WATTAGE 1/16W
J 2
(-1825 -1100);
DISPLAY 0.510638 (-1825 -1100);
FORCEPROP 1 LAST VALUE 1K
J 2
(-1925 -1225);
DISPLAY 0.638298 (-1925 -1225);
FORCEPROP 1 LAST PACK_TYPE 0402LF
J 0
(-2175 -1100);
DISPLAY 0.510638 (-2175 -1100);
FORCEPROP 1 LAST $LOCATION R1008
J 0
(-2350 -1225);
DISPLAY 0.787234 (-2350 -1225);
FORCEPROP 1 LASTPIN (-2200 -1225) $PN 1
J 0
(-2188 -1213);
DISPLAY 0.787234 (-2188 -1213);
FORCEPROP 1 LASTPIN (-2000 -1225) $PN 2
J 0
(-2038 -1213);
DISPLAY 0.787234 (-2038 -1213);
FORCEPROP 2 LAST CDS_LIB pure_quanta
J 0
(-2100 -1225);
PAINT MONO (-2100 -1225);
DISPLAY INVISIBLE (-2100 -1225);
FORCEPROP 1 LAST PATH I139
J 0
(-2150 -1075);
DISPLAY 0.978723 (-2150 -1075);
PAINT WHITE (-2150 -1075);
DISPLAY INVISIBLE (-2150 -1075);
FORCEPROP 2 LAST CDS_LOCATION R1008
J 0
(-2150 -1025);
DISPLAY 1.021277 (-2150 -1025);
DISPLAY INVISIBLE (-2150 -1025);
FORCEPROP 2 LAST $SEC 1
J 0
(-2150 -1025);
DISPLAY 0.680851 (-2150 -1025);
PAINT MONO (-2150 -1025);
DISPLAY INVISIBLE (-2150 -1025);
FORCEPROP 2 LAST CDS_SEC 1
J 0
(-2150 -1025);
DISPLAY 1.021277 (-2150 -1025);
DISPLAY INVISIBLE (-2150 -1025);
FORCEADD UNIVERSAL_POWER..1
(-2400 -1000);
FORCEPROP 3 LASTPIN (-2400 -1050) SIG_NAME PVNN_TERM_CPU1\g
J 0
(-2390 -1040);
DISPLAY 0.659574 (-2390 -1040);
PAINT MONO (-2390 -1040);
DISPLAY INVISIBLE (-2390 -1040);
FORCEPROP 1 LAST HDL_POWER PVNN_TERM_CPU1
J 1
(-2400 -950);
DISPLAY 0.872340 (-2400 -950);
PAINT GREEN (-2400 -950);
FORCEPROP 2 LAST CDS_LIB logical_power
J 0
(-2400 -1000);
PAINT MONO (-2400 -1000);
DISPLAY INVISIBLE (-2400 -1000);
FORCEPROP 1 LAST PATH I141
J 0
(-2350 -975);
DISPLAY 0.872340 (-2350 -975);
PAINT AQUA (-2350 -975);
DISPLAY INVISIBLE (-2350 -975);
FORCEADD OFFPAGE..1
R 2
(1550 2250);
FORCEPROP 2 LAST $XR1 214 
J 0
(1826 2250);
DISPLAY 0.638298 (1826 2250);
PAINT MONO (1826 2250);
FORCEPROP 2 LAST $XR0 13 
J 0
(1736 2250);
DISPLAY 0.638298 (1736 2250);
PAINT MONO (1736 2250);
FORCEPROP 2 LAST CDS_LIB standard
J 0
(1550 2250);
PAINT MONO (1550 2250);
DISPLAY INVISIBLE (1550 2250);
FORCEPROP 1 LAST OFFPAGE TRUE
J 2
(1225 2125);
DISPLAY 0.872340 (1225 2125);
DISPLAY INVISIBLE (1225 2125);
FORCEPROP 1 LAST COMMENT_BODY TRUE
J 2
(1425 2150);
DISPLAY 0.872340 (1425 2150);
PAINT GREEN (1425 2150);
DISPLAY INVISIBLE (1425 2150);
FORCEPROP 2 LAST PATH I142
J 0
(1875 2300);
DISPLAY 1.021277 (1875 2300);
DISPLAY INVISIBLE (1875 2300);
FORCEADD OFFPAGE..1
R 2
(1550 2125);
FORCEPROP 2 LAST $XR1 214 
J 0
(1826 2125);
DISPLAY 0.638298 (1826 2125);
PAINT MONO (1826 2125);
FORCEPROP 2 LAST $XR0 13 
J 0
(1736 2125);
DISPLAY 0.638298 (1736 2125);
PAINT MONO (1736 2125);
FORCEPROP 2 LAST CDS_LIB standard
J 0
(1550 2125);
PAINT MONO (1550 2125);
DISPLAY INVISIBLE (1550 2125);
FORCEPROP 1 LAST OFFPAGE TRUE
J 2
(1225 2000);
DISPLAY 0.872340 (1225 2000);
DISPLAY INVISIBLE (1225 2000);
FORCEPROP 1 LAST COMMENT_BODY TRUE
J 2
(1425 2025);
DISPLAY 0.872340 (1425 2025);
PAINT GREEN (1425 2025);
DISPLAY INVISIBLE (1425 2025);
FORCEPROP 2 LAST PATH I143
J 0
(1875 2175);
DISPLAY 1.021277 (1875 2175);
DISPLAY INVISIBLE (1875 2175);
FORCEADD OFFPAGE..1
R 2
(1550 1875);
FORCEPROP 2 LAST $XR1 214 
J 0
(1826 1875);
DISPLAY 0.638298 (1826 1875);
PAINT MONO (1826 1875);
FORCEPROP 2 LAST $XR0 13 
J 0
(1736 1875);
DISPLAY 0.638298 (1736 1875);
PAINT MONO (1736 1875);
FORCEPROP 2 LAST CDS_LIB standard
J 0
(1550 1875);
PAINT MONO (1550 1875);
DISPLAY INVISIBLE (1550 1875);
FORCEPROP 1 LAST OFFPAGE TRUE
J 2
(1225 1750);
DISPLAY 0.872340 (1225 1750);
DISPLAY INVISIBLE (1225 1750);
FORCEPROP 1 LAST COMMENT_BODY TRUE
J 2
(1425 1775);
DISPLAY 0.872340 (1425 1775);
PAINT GREEN (1425 1775);
DISPLAY INVISIBLE (1425 1775);
FORCEPROP 2 LAST PATH I144
J 0
(1875 1925);
DISPLAY 1.021277 (1875 1925);
DISPLAY INVISIBLE (1875 1925);
FORCEADD OFFPAGE..1
R 2
(1550 2000);
FORCEPROP 2 LAST $XR1 214 
J 0
(1826 2000);
DISPLAY 0.638298 (1826 2000);
PAINT MONO (1826 2000);
FORCEPROP 2 LAST $XR0 13 
J 0
(1736 2000);
DISPLAY 0.638298 (1736 2000);
PAINT MONO (1736 2000);
FORCEPROP 2 LAST CDS_LIB standard
J 0
(1550 2000);
PAINT MONO (1550 2000);
DISPLAY INVISIBLE (1550 2000);
FORCEPROP 1 LAST OFFPAGE TRUE
J 2
(1225 1875);
DISPLAY 0.872340 (1225 1875);
DISPLAY INVISIBLE (1225 1875);
FORCEPROP 1 LAST COMMENT_BODY TRUE
J 2
(1425 1900);
DISPLAY 0.872340 (1425 1900);
PAINT GREEN (1425 1900);
DISPLAY INVISIBLE (1425 1900);
FORCEPROP 2 LAST PATH I145
J 0
(1875 2050);
DISPLAY 1.021277 (1875 2050);
DISPLAY INVISIBLE (1875 2050);
FORCEADD OFFPAGE..1
R 2
(1550 1750);
FORCEPROP 2 LAST $XR1 214 
J 0
(1826 1750);
DISPLAY 0.638298 (1826 1750);
PAINT MONO (1826 1750);
FORCEPROP 2 LAST $XR0 13 
J 0
(1736 1750);
DISPLAY 0.638298 (1736 1750);
PAINT MONO (1736 1750);
FORCEPROP 2 LAST CDS_LIB standard
J 0
(1550 1750);
PAINT MONO (1550 1750);
DISPLAY INVISIBLE (1550 1750);
FORCEPROP 1 LAST OFFPAGE TRUE
J 2
(1225 1625);
DISPLAY 0.872340 (1225 1625);
DISPLAY INVISIBLE (1225 1625);
FORCEPROP 1 LAST COMMENT_BODY TRUE
J 2
(1425 1650);
DISPLAY 0.872340 (1425 1650);
PAINT GREEN (1425 1650);
DISPLAY INVISIBLE (1425 1650);
FORCEPROP 2 LAST PATH I146
J 0
(1875 1800);
DISPLAY 1.021277 (1875 1800);
DISPLAY INVISIBLE (1875 1800);
FORCEADD Q_RES..1
(250 2250);
FORCEPROP 1 LAST PART_NUMBER CS31002FB08
J 0
(150 2300);
DISPLAY 0.510638 (150 2300);
DISPLAY INVISIBLE (150 2300);
FORCEPROP 1 LAST WATTAGE 1/16W
J 2
(450 2325);
DISPLAY 0.510638 (450 2325);
FORCEPROP 1 LAST MATERIAL CHIP
J 0
(575 2250);
DISPLAY 0.638298 (575 2250);
FORCEPROP 1 LAST VALUE 10K
J 2
(450 2250);
DISPLAY 0.638298 (450 2250);
FORCEPROP 1 LAST PACK_TYPE 0402LF
J 0
(150 2325);
DISPLAY 0.510638 (150 2325);
FORCEPROP 1 LAST TOLERANCE 1%
J 0
(475 2250);
DISPLAY 0.638298 (475 2250);
FORCEPROP 1 LAST $LOCATION R283
J 0
(25 2250);
DISPLAY 0.787234 (25 2250);
FORCEPROP 1 LASTPIN (150 2250) $PN 1
J 0
(162 2262);
DISPLAY 0.787234 (162 2262);
FORCEPROP 1 LASTPIN (350 2250) $PN 2
J 0
(312 2262);
DISPLAY 0.787234 (312 2262);
FORCEPROP 2 LAST CDS_LIB pure_quanta
J 0
(250 2250);
PAINT MONO (250 2250);
DISPLAY INVISIBLE (250 2250);
FORCEPROP 1 LAST PATH I147
J 0
(200 2400);
DISPLAY 0.978723 (200 2400);
PAINT WHITE (200 2400);
DISPLAY INVISIBLE (200 2400);
FORCEPROP 2 LAST CDS_LOCATION R283
J 0
(200 2450);
DISPLAY 1.021277 (200 2450);
DISPLAY INVISIBLE (200 2450);
FORCEPROP 2 LAST $SEC 1
J 0
(200 2450);
DISPLAY 0.680851 (200 2450);
PAINT MONO (200 2450);
DISPLAY INVISIBLE (200 2450);
FORCEPROP 2 LAST CDS_SEC 1
J 0
(200 2450);
DISPLAY 1.021277 (200 2450);
DISPLAY INVISIBLE (200 2450);
FORCEADD Q_RES..1
(250 2125);
FORCEPROP 1 LAST PART_NUMBER CS31002FB08
J 0
(150 2175);
DISPLAY 0.510638 (150 2175);
DISPLAY INVISIBLE (150 2175);
FORCEPROP 1 LAST MATERIAL CHIP
J 0
(575 2125);
DISPLAY 0.638298 (575 2125);
FORCEPROP 1 LAST TOLERANCE 1%
J 0
(475 2125);
DISPLAY 0.638298 (475 2125);
FORCEPROP 1 LAST VALUE 10K
J 2
(450 2125);
DISPLAY 0.638298 (450 2125);
FORCEPROP 1 LAST $LOCATION R284
J 0
(25 2125);
DISPLAY 0.787234 (25 2125);
FORCEPROP 1 LASTPIN (150 2125) $PN 1
J 0
(162 2137);
DISPLAY 0.787234 (162 2137);
FORCEPROP 1 LASTPIN (350 2125) $PN 2
J 0
(312 2137);
DISPLAY 0.787234 (312 2137);
FORCEPROP 2 LAST CDS_LIB pure_quanta
J 0
(250 2125);
PAINT MONO (250 2125);
DISPLAY INVISIBLE (250 2125);
FORCEPROP 1 LAST PACK_TYPE 0402LF
J 0
(150 2200);
DISPLAY 0.510638 (150 2200);
DISPLAY INVISIBLE (150 2200);
FORCEPROP 1 LAST WATTAGE 1/16W
J 2
(450 2200);
DISPLAY 0.510638 (450 2200);
DISPLAY INVISIBLE (450 2200);
FORCEPROP 1 LAST PATH I148
J 0
(200 2275);
DISPLAY 0.978723 (200 2275);
PAINT WHITE (200 2275);
DISPLAY INVISIBLE (200 2275);
FORCEPROP 2 LAST CDS_LOCATION R284
J 0
(200 2325);
DISPLAY 1.021277 (200 2325);
DISPLAY INVISIBLE (200 2325);
FORCEPROP 2 LAST $SEC 1
J 0
(200 2325);
DISPLAY 0.680851 (200 2325);
PAINT MONO (200 2325);
DISPLAY INVISIBLE (200 2325);
FORCEPROP 2 LAST CDS_SEC 1
J 0
(200 2325);
DISPLAY 1.021277 (200 2325);
DISPLAY INVISIBLE (200 2325);
FORCEADD UNIVERSAL_POWER..1
(-50 2375);
FORCEPROP 3 LASTPIN (-50 2325) SIG_NAME P3V3_AUX\g
J 0
(-40 2335);
DISPLAY 0.659574 (-40 2335);
PAINT MONO (-40 2335);
DISPLAY INVISIBLE (-40 2335);
FORCEPROP 1 LAST HDL_POWER P3V3_AUX
J 1
(-50 2425);
DISPLAY 0.872340 (-50 2425);
PAINT GREEN (-50 2425);
FORCEPROP 2 LAST CDS_LIB logical_power
J 0
(-50 2375);
DISPLAY INVISIBLE (-50 2375);
FORCEPROP 1 LAST PATH I149
J 0
(0 2400);
DISPLAY 0.872340 (0 2400);
PAINT AQUA (0 2400);
DISPLAY INVISIBLE (0 2400);
FORCEADD Q_RES..1
(250 2000);
FORCEPROP 1 LAST PART_NUMBER CS31002FB08
J 0
(150 2050);
DISPLAY 0.510638 (150 2050);
DISPLAY INVISIBLE (150 2050);
FORCEPROP 1 LAST VALUE 10K
J 2
(450 2000);
DISPLAY 0.638298 (450 2000);
FORCEPROP 1 LAST TOLERANCE 1%
J 0
(475 2000);
DISPLAY 0.638298 (475 2000);
FORCEPROP 1 LAST MATERIAL CHIP
J 0
(575 2000);
DISPLAY 0.638298 (575 2000);
FORCEPROP 1 LAST $LOCATION R285
J 0
(25 2000);
DISPLAY 0.787234 (25 2000);
FORCEPROP 1 LASTPIN (150 2000) $PN 1
J 0
(162 2012);
DISPLAY 0.787234 (162 2012);
FORCEPROP 1 LASTPIN (350 2000) $PN 2
J 0
(312 2012);
DISPLAY 0.787234 (312 2012);
FORCEPROP 2 LAST CDS_LIB pure_quanta
J 0
(250 2000);
PAINT MONO (250 2000);
DISPLAY INVISIBLE (250 2000);
FORCEPROP 1 LAST PACK_TYPE 0402LF
J 0
(150 2075);
DISPLAY 0.510638 (150 2075);
DISPLAY INVISIBLE (150 2075);
FORCEPROP 1 LAST WATTAGE 1/16W
J 2
(450 2075);
DISPLAY 0.510638 (450 2075);
DISPLAY INVISIBLE (450 2075);
FORCEPROP 1 LAST PATH I150
J 0
(200 2150);
DISPLAY 0.978723 (200 2150);
PAINT WHITE (200 2150);
DISPLAY INVISIBLE (200 2150);
FORCEPROP 2 LAST CDS_LOCATION R285
J 0
(200 2200);
DISPLAY 1.021277 (200 2200);
DISPLAY INVISIBLE (200 2200);
FORCEPROP 2 LAST $SEC 1
J 0
(200 2200);
DISPLAY 0.680851 (200 2200);
PAINT MONO (200 2200);
DISPLAY INVISIBLE (200 2200);
FORCEPROP 2 LAST CDS_SEC 1
J 0
(200 2200);
DISPLAY 1.021277 (200 2200);
DISPLAY INVISIBLE (200 2200);
FORCEADD Q_RES..1
(250 1875);
FORCEPROP 1 LAST PART_NUMBER CS31002FB08
J 0
(150 1925);
DISPLAY 0.510638 (150 1925);
DISPLAY INVISIBLE (150 1925);
FORCEPROP 1 LAST TOLERANCE 1%
J 0
(475 1875);
DISPLAY 0.638298 (475 1875);
FORCEPROP 1 LAST VALUE 10K
J 2
(450 1875);
DISPLAY 0.638298 (450 1875);
FORCEPROP 1 LAST MATERIAL CHIP
J 0
(575 1875);
DISPLAY 0.638298 (575 1875);
FORCEPROP 1 LAST $LOCATION R286
J 0
(25 1875);
DISPLAY 0.787234 (25 1875);
FORCEPROP 1 LASTPIN (150 1875) $PN 1
J 0
(162 1887);
DISPLAY 0.787234 (162 1887);
FORCEPROP 1 LASTPIN (350 1875) $PN 2
J 0
(312 1887);
DISPLAY 0.787234 (312 1887);
FORCEPROP 2 LAST CDS_LIB pure_quanta
J 0
(250 1875);
PAINT MONO (250 1875);
DISPLAY INVISIBLE (250 1875);
FORCEPROP 1 LAST WATTAGE 1/16W
J 2
(450 1950);
DISPLAY 0.510638 (450 1950);
DISPLAY INVISIBLE (450 1950);
FORCEPROP 1 LAST PACK_TYPE 0402LF
J 0
(150 1950);
DISPLAY 0.510638 (150 1950);
DISPLAY INVISIBLE (150 1950);
FORCEPROP 1 LAST PATH I151
J 0
(200 2025);
DISPLAY 0.978723 (200 2025);
PAINT WHITE (200 2025);
DISPLAY INVISIBLE (200 2025);
FORCEPROP 2 LAST CDS_LOCATION R286
J 0
(200 2075);
DISPLAY 1.021277 (200 2075);
DISPLAY INVISIBLE (200 2075);
FORCEPROP 2 LAST $SEC 1
J 0
(200 2075);
DISPLAY 0.680851 (200 2075);
PAINT MONO (200 2075);
DISPLAY INVISIBLE (200 2075);
FORCEPROP 2 LAST CDS_SEC 1
J 0
(200 2075);
DISPLAY 1.021277 (200 2075);
DISPLAY INVISIBLE (200 2075);
FORCEADD Q_RES..1
(250 1750);
FORCEPROP 1 LAST PART_NUMBER CS31002FB08
J 0
(150 1800);
DISPLAY 0.510638 (150 1800);
DISPLAY INVISIBLE (150 1800);
FORCEPROP 1 LAST MATERIAL CHIP
J 0
(575 1750);
DISPLAY 0.638298 (575 1750);
FORCEPROP 1 LAST TOLERANCE 1%
J 0
(475 1750);
DISPLAY 0.638298 (475 1750);
FORCEPROP 1 LAST VALUE 10K
J 2
(450 1750);
DISPLAY 0.638298 (450 1750);
FORCEPROP 1 LAST $LOCATION R287
J 0
(25 1750);
DISPLAY 0.787234 (25 1750);
FORCEPROP 1 LASTPIN (150 1750) $PN 1
J 0
(162 1762);
DISPLAY 0.787234 (162 1762);
FORCEPROP 1 LASTPIN (350 1750) $PN 2
J 0
(312 1762);
DISPLAY 0.787234 (312 1762);
FORCEPROP 2 LAST CDS_LIB pure_quanta
J 0
(250 1750);
PAINT MONO (250 1750);
DISPLAY INVISIBLE (250 1750);
FORCEPROP 1 LAST PACK_TYPE 0402LF
J 0
(150 1825);
DISPLAY 0.510638 (150 1825);
DISPLAY INVISIBLE (150 1825);
FORCEPROP 1 LAST WATTAGE 1/16W
J 2
(450 1825);
DISPLAY 0.510638 (450 1825);
DISPLAY INVISIBLE (450 1825);
FORCEPROP 1 LAST PATH I152
J 0
(200 1900);
DISPLAY 0.978723 (200 1900);
PAINT WHITE (200 1900);
DISPLAY INVISIBLE (200 1900);
FORCEPROP 2 LAST CDS_LOCATION R287
J 0
(200 1950);
DISPLAY 1.021277 (200 1950);
DISPLAY INVISIBLE (200 1950);
FORCEPROP 2 LAST $SEC 1
J 0
(200 1950);
DISPLAY 0.680851 (200 1950);
PAINT MONO (200 1950);
DISPLAY INVISIBLE (200 1950);
FORCEPROP 2 LAST CDS_SEC 1
J 0
(200 1950);
DISPLAY 1.021277 (200 1950);
DISPLAY INVISIBLE (200 1950);
FORCEADD OFFPAGE..2
(-700 2450);
FORCEPROP 2 LAST $XR1 13 
J 0
(-391 2450);
DISPLAY 0.638298 (-391 2450);
PAINT MONO (-391 2450);
FORCEPROP 2 LAST $XR0 119 
J 0
(-511 2450);
DISPLAY 0.638298 (-511 2450);
PAINT MONO (-511 2450);
FORCEPROP 2 LAST CDS_LIB standard
J 0
(-700 2450);
DISPLAY INVISIBLE (-700 2450);
FORCEPROP 1 LAST OFFPAGE TRUE
J 0
(-375 2325);
DISPLAY 0.872340 (-375 2325);
PAINT GREEN (-375 2325);
DISPLAY INVISIBLE (-375 2325);
FORCEPROP 1 LAST COMMENT_BODY TRUE
J 0
(-745 2355);
DISPLAY 0.872340 (-745 2355);
PAINT GREEN (-745 2355);
DISPLAY INVISIBLE (-745 2355);
FORCEPROP 2 LAST PATH I155
J 0
(-500 2500);
DISPLAY 1.021277 (-500 2500);
DISPLAY INVISIBLE (-500 2500);
FORCEADD Q_RES..1
(-2075 2450);
FORCEPROP 1 LAST PART_NUMBER CS12402FB01
J 0
(-2175 2500);
DISPLAY 0.510638 (-2175 2500);
DISPLAY INVISIBLE (-2175 2500);
FORCEPROP 1 LAST VALUE 240
J 2
(-1875 2450);
DISPLAY 0.638298 (-1875 2450);
FORCEPROP 1 LAST MATERIAL EMPTY
J 0
(-1750 2450);
DISPLAY 0.638298 (-1750 2450);
PAINT RED (-1750 2450);
FORCEPROP 1 LAST TOLERANCE 1%
J 0
(-1850 2450);
DISPLAY 0.638298 (-1850 2450);
FORCEPROP 1 LAST $LOCATION R1232
J 0
(-2300 2450);
DISPLAY 0.787234 (-2300 2450);
FORCEPROP 1 LASTPIN (-2175 2450) $PN 1
J 0
(-2163 2462);
DISPLAY 0.787234 (-2163 2462);
FORCEPROP 1 LASTPIN (-1975 2450) $PN 2
J 0
(-2013 2462);
DISPLAY 0.787234 (-2013 2462);
FORCEPROP 2 LAST CDS_LIB pure_quanta
J 0
(-2075 2450);
PAINT MONO (-2075 2450);
DISPLAY INVISIBLE (-2075 2450);
FORCEPROP 1 LAST WATTAGE 1/16W
J 2
(-1900 2525);
DISPLAY 0.510638 (-1900 2525);
DISPLAY INVISIBLE (-1900 2525);
FORCEPROP 1 LAST PACK_TYPE 0402LF
J 0
(-2175 2525);
DISPLAY 0.510638 (-2175 2525);
DISPLAY INVISIBLE (-2175 2525);
FORCEPROP 1 LAST PATH I156
J 0
(-2125 2600);
DISPLAY 0.978723 (-2125 2600);
PAINT WHITE (-2125 2600);
DISPLAY INVISIBLE (-2125 2600);
FORCEPROP 2 LAST CDS_LOCATION R1232
J 0
(-2125 2650);
DISPLAY 1.021277 (-2125 2650);
DISPLAY INVISIBLE (-2125 2650);
FORCEPROP 2 LAST $SEC 1
J 0
(-2125 2650);
DISPLAY 0.680851 (-2125 2650);
PAINT MONO (-2125 2650);
DISPLAY INVISIBLE (-2125 2650);
FORCEPROP 2 LAST CDS_SEC 1
J 0
(-2125 2650);
DISPLAY 1.021277 (-2125 2650);
DISPLAY INVISIBLE (-2125 2650);
FORCEADD OFFPAGE..2
(-700 2325);
FORCEPROP 2 LAST $XR1 13 
J 0
(-391 2325);
DISPLAY 0.638298 (-391 2325);
PAINT MONO (-391 2325);
FORCEPROP 2 LAST $XR0 119 
J 0
(-511 2325);
DISPLAY 0.638298 (-511 2325);
PAINT MONO (-511 2325);
FORCEPROP 2 LAST CDS_LIB standard
J 0
(-700 2325);
DISPLAY INVISIBLE (-700 2325);
FORCEPROP 1 LAST OFFPAGE TRUE
J 0
(-375 2200);
DISPLAY 0.872340 (-375 2200);
PAINT GREEN (-375 2200);
DISPLAY INVISIBLE (-375 2200);
FORCEPROP 1 LAST COMMENT_BODY TRUE
J 0
(-745 2230);
DISPLAY 0.872340 (-745 2230);
PAINT GREEN (-745 2230);
DISPLAY INVISIBLE (-745 2230);
FORCEPROP 2 LAST PATH I157
J 0
(-500 2375);
DISPLAY 1.021277 (-500 2375);
DISPLAY INVISIBLE (-500 2375);
FORCEADD Q_RES..1
(-2075 2325);
FORCEPROP 1 LAST PART_NUMBER CS12402FB01
J 0
(-2175 2375);
DISPLAY 0.510638 (-2175 2375);
DISPLAY INVISIBLE (-2175 2375);
FORCEPROP 1 LAST MATERIAL EMPTY
J 0
(-1750 2325);
DISPLAY 0.638298 (-1750 2325);
PAINT RED (-1750 2325);
FORCEPROP 1 LAST TOLERANCE 1%
J 0
(-1850 2325);
DISPLAY 0.638298 (-1850 2325);
FORCEPROP 1 LAST VALUE 240
J 2
(-1875 2325);
DISPLAY 0.638298 (-1875 2325);
FORCEPROP 1 LAST $LOCATION R1233
J 0
(-2300 2325);
DISPLAY 0.787234 (-2300 2325);
FORCEPROP 1 LASTPIN (-2175 2325) $PN 1
J 0
(-2163 2337);
DISPLAY 0.787234 (-2163 2337);
FORCEPROP 1 LASTPIN (-1975 2325) $PN 2
J 0
(-2013 2337);
DISPLAY 0.787234 (-2013 2337);
FORCEPROP 2 LAST CDS_LIB pure_quanta
J 0
(-2075 2325);
PAINT MONO (-2075 2325);
DISPLAY INVISIBLE (-2075 2325);
FORCEPROP 1 LAST WATTAGE 1/16W
J 2
(-1900 2400);
DISPLAY 0.510638 (-1900 2400);
DISPLAY INVISIBLE (-1900 2400);
FORCEPROP 1 LAST PACK_TYPE 0402LF
J 0
(-2175 2400);
DISPLAY 0.510638 (-2175 2400);
DISPLAY INVISIBLE (-2175 2400);
FORCEPROP 1 LAST PATH I158
J 0
(-2125 2475);
DISPLAY 0.978723 (-2125 2475);
PAINT WHITE (-2125 2475);
DISPLAY INVISIBLE (-2125 2475);
FORCEPROP 2 LAST CDS_LOCATION R1233
J 0
(-2125 2525);
DISPLAY 1.021277 (-2125 2525);
DISPLAY INVISIBLE (-2125 2525);
FORCEPROP 2 LAST $SEC 1
J 0
(-2125 2525);
DISPLAY 0.680851 (-2125 2525);
PAINT MONO (-2125 2525);
DISPLAY INVISIBLE (-2125 2525);
FORCEPROP 2 LAST CDS_SEC 1
J 0
(-2125 2525);
DISPLAY 1.021277 (-2125 2525);
DISPLAY INVISIBLE (-2125 2525);
FORCEADD OFFPAGE..2
(1675 3100);
FORCEPROP 2 LAST $XR0 13 
J 0
(1864 3100);
DISPLAY 0.638298 (1864 3100);
PAINT MONO (1864 3100);
FORCEPROP 2 LAST CDS_LIB standard
J 0
(1675 3100);
DISPLAY INVISIBLE (1675 3100);
FORCEPROP 1 LAST OFFPAGE TRUE
J 0
(2000 2975);
DISPLAY 0.872340 (2000 2975);
PAINT GREEN (2000 2975);
DISPLAY INVISIBLE (2000 2975);
FORCEPROP 1 LAST COMMENT_BODY TRUE
J 0
(1630 3005);
DISPLAY 0.872340 (1630 3005);
PAINT GREEN (1630 3005);
DISPLAY INVISIBLE (1630 3005);
FORCEPROP 2 LAST PATH I159
J 0
(1875 3150);
DISPLAY 1.021277 (1875 3150);
DISPLAY INVISIBLE (1875 3150);
FORCEADD Q_RES..1
(275 3100);
FORCEPROP 1 LAST PART_NUMBER CS12402FB01
J 0
(175 3150);
DISPLAY 0.510638 (175 3150);
DISPLAY INVISIBLE (175 3150);
FORCEPROP 1 LAST VALUE 240
J 2
(475 3100);
DISPLAY 0.638298 (475 3100);
FORCEPROP 1 LAST MATERIAL EMPTY
J 0
(600 3100);
DISPLAY 0.638298 (600 3100);
PAINT RED (600 3100);
FORCEPROP 1 LAST TOLERANCE 1%
J 0
(500 3100);
DISPLAY 0.638298 (500 3100);
FORCEPROP 1 LAST $LOCATION R1237
J 0
(50 3100);
DISPLAY 0.787234 (50 3100);
FORCEPROP 1 LASTPIN (175 3100) $PN 1
J 0
(187 3112);
DISPLAY 0.787234 (187 3112);
FORCEPROP 1 LASTPIN (375 3100) $PN 2
J 0
(337 3112);
DISPLAY 0.787234 (337 3112);
FORCEPROP 2 LAST CDS_LIB pure_quanta
J 0
(275 3100);
PAINT MONO (275 3100);
DISPLAY INVISIBLE (275 3100);
FORCEPROP 1 LAST WATTAGE 1/16W
J 2
(450 3175);
DISPLAY 0.510638 (450 3175);
DISPLAY INVISIBLE (450 3175);
FORCEPROP 1 LAST PACK_TYPE 0402LF
J 0
(175 3175);
DISPLAY 0.510638 (175 3175);
DISPLAY INVISIBLE (175 3175);
FORCEPROP 1 LAST PATH I160
J 0
(225 3250);
DISPLAY 0.978723 (225 3250);
PAINT WHITE (225 3250);
DISPLAY INVISIBLE (225 3250);
FORCEPROP 2 LAST CDS_LOCATION R1237
J 0
(225 3300);
DISPLAY 1.021277 (225 3300);
DISPLAY INVISIBLE (225 3300);
FORCEPROP 2 LAST $SEC 1
J 0
(225 3300);
DISPLAY 0.680851 (225 3300);
PAINT MONO (225 3300);
DISPLAY INVISIBLE (225 3300);
FORCEPROP 2 LAST CDS_SEC 1
J 0
(225 3300);
DISPLAY 1.021277 (225 3300);
DISPLAY INVISIBLE (225 3300);
FORCEADD Q_RES..1
(275 2975);
FORCEPROP 1 LAST PART_NUMBER CS12402FB01
J 0
(175 3025);
DISPLAY 0.510638 (175 3025);
DISPLAY INVISIBLE (175 3025);
FORCEPROP 1 LAST MATERIAL EMPTY
J 0
(600 2975);
DISPLAY 0.638298 (600 2975);
PAINT RED (600 2975);
FORCEPROP 1 LAST VALUE 240
J 2
(475 2975);
DISPLAY 0.638298 (475 2975);
FORCEPROP 1 LAST TOLERANCE 1%
J 0
(500 2975);
DISPLAY 0.638298 (500 2975);
FORCEPROP 1 LAST $LOCATION R1238
J 0
(50 2975);
DISPLAY 0.787234 (50 2975);
FORCEPROP 1 LASTPIN (175 2975) $PN 1
J 0
(187 2987);
DISPLAY 0.787234 (187 2987);
FORCEPROP 1 LASTPIN (375 2975) $PN 2
J 0
(337 2987);
DISPLAY 0.787234 (337 2987);
FORCEPROP 1 LAST PACK_TYPE 0402LF
J 0
(175 3050);
DISPLAY 0.510638 (175 3050);
DISPLAY INVISIBLE (175 3050);
FORCEPROP 1 LAST WATTAGE 1/16W
J 2
(450 3050);
DISPLAY 0.510638 (450 3050);
DISPLAY INVISIBLE (450 3050);
FORCEPROP 2 LAST CDS_LIB pure_quanta
J 0
(275 2975);
PAINT MONO (275 2975);
DISPLAY INVISIBLE (275 2975);
FORCEPROP 1 LAST PATH I161
J 0
(225 3125);
DISPLAY 0.978723 (225 3125);
PAINT WHITE (225 3125);
DISPLAY INVISIBLE (225 3125);
FORCEPROP 2 LAST CDS_LOCATION R1238
J 0
(225 3175);
DISPLAY 1.021277 (225 3175);
DISPLAY INVISIBLE (225 3175);
FORCEPROP 2 LAST $SEC 1
J 0
(225 3175);
DISPLAY 0.680851 (225 3175);
PAINT MONO (225 3175);
DISPLAY INVISIBLE (225 3175);
FORCEPROP 2 LAST CDS_SEC 1
J 0
(225 3175);
DISPLAY 1.021277 (225 3175);
DISPLAY INVISIBLE (225 3175);
FORCEADD OFFPAGE..2
(1675 2975);
FORCEPROP 2 LAST $XR1 13 
J 0
(1984 2975);
DISPLAY 0.638298 (1984 2975);
PAINT MONO (1984 2975);
FORCEPROP 2 LAST $XR0 119 
J 0
(1864 2975);
DISPLAY 0.638298 (1864 2975);
PAINT MONO (1864 2975);
FORCEPROP 2 LAST CDS_LIB standard
J 0
(1675 2975);
DISPLAY INVISIBLE (1675 2975);
FORCEPROP 1 LAST OFFPAGE TRUE
J 0
(2000 2850);
DISPLAY 0.872340 (2000 2850);
PAINT GREEN (2000 2850);
DISPLAY INVISIBLE (2000 2850);
FORCEPROP 1 LAST COMMENT_BODY TRUE
J 0
(1630 2880);
DISPLAY 0.872340 (1630 2880);
PAINT GREEN (1630 2880);
DISPLAY INVISIBLE (1630 2880);
FORCEPROP 2 LAST PATH I162
J 0
(1875 3025);
DISPLAY 1.021277 (1875 3025);
DISPLAY INVISIBLE (1875 3025);
FORCEADD Q_RES..1
(275 2850);
FORCEPROP 1 LAST PART_NUMBER CS12402FB01
J 0
(175 2900);
DISPLAY 0.510638 (175 2900);
DISPLAY INVISIBLE (175 2900);
FORCEPROP 1 LAST MATERIAL EMPTY
J 0
(600 2850);
DISPLAY 0.638298 (600 2850);
PAINT RED (600 2850);
FORCEPROP 1 LAST VALUE 240
J 2
(475 2850);
DISPLAY 0.638298 (475 2850);
FORCEPROP 1 LAST TOLERANCE 1%
J 0
(500 2850);
DISPLAY 0.638298 (500 2850);
FORCEPROP 1 LAST $LOCATION R1239
J 0
(50 2850);
DISPLAY 0.787234 (50 2850);
FORCEPROP 1 LASTPIN (175 2850) $PN 1
J 0
(187 2862);
DISPLAY 0.787234 (187 2862);
FORCEPROP 1 LASTPIN (375 2850) $PN 2
J 0
(337 2862);
DISPLAY 0.787234 (337 2862);
FORCEPROP 1 LAST PACK_TYPE 0402LF
J 0
(175 2925);
DISPLAY 0.510638 (175 2925);
DISPLAY INVISIBLE (175 2925);
FORCEPROP 1 LAST WATTAGE 1/16W
J 2
(450 2925);
DISPLAY 0.510638 (450 2925);
DISPLAY INVISIBLE (450 2925);
FORCEPROP 2 LAST CDS_LIB pure_quanta
J 0
(275 2850);
PAINT MONO (275 2850);
DISPLAY INVISIBLE (275 2850);
FORCEPROP 1 LAST PATH I163
J 0
(225 3000);
DISPLAY 0.978723 (225 3000);
PAINT WHITE (225 3000);
DISPLAY INVISIBLE (225 3000);
FORCEPROP 2 LAST CDS_LOCATION R1239
J 0
(225 3050);
DISPLAY 1.021277 (225 3050);
DISPLAY INVISIBLE (225 3050);
FORCEPROP 2 LAST $SEC 1
J 0
(225 3050);
DISPLAY 0.680851 (225 3050);
PAINT MONO (225 3050);
DISPLAY INVISIBLE (225 3050);
FORCEPROP 2 LAST CDS_SEC 1
J 0
(225 3050);
DISPLAY 1.021277 (225 3050);
DISPLAY INVISIBLE (225 3050);
FORCEADD OFFPAGE..2
(1675 2850);
FORCEPROP 2 LAST $XR1 13 
J 0
(1984 2850);
DISPLAY 0.638298 (1984 2850);
PAINT MONO (1984 2850);
FORCEPROP 2 LAST $XR0 119 
J 0
(1864 2850);
DISPLAY 0.638298 (1864 2850);
PAINT MONO (1864 2850);
FORCEPROP 2 LAST CDS_LIB standard
J 0
(1675 2850);
DISPLAY INVISIBLE (1675 2850);
FORCEPROP 1 LAST OFFPAGE TRUE
J 0
(2000 2725);
DISPLAY 0.872340 (2000 2725);
PAINT GREEN (2000 2725);
DISPLAY INVISIBLE (2000 2725);
FORCEPROP 1 LAST COMMENT_BODY TRUE
J 0
(1630 2755);
DISPLAY 0.872340 (1630 2755);
PAINT GREEN (1630 2755);
DISPLAY INVISIBLE (1630 2755);
FORCEPROP 2 LAST PATH I164
J 0
(1875 2900);
DISPLAY 1.021277 (1875 2900);
DISPLAY INVISIBLE (1875 2900);
FORCEADD OFFPAGE..2
(-750 -650);
FORCEPROP 2 LAST $XR1 44 
J 0
(-441 -650);
DISPLAY 0.638298 (-441 -650);
PAINT MONO (-441 -650);
FORCEPROP 2 LAST $XR0 119 
J 0
(-561 -650);
DISPLAY 0.638298 (-561 -650);
PAINT MONO (-561 -650);
FORCEPROP 2 LAST CDS_LIB standard
J 0
(-750 -650);
DISPLAY INVISIBLE (-750 -650);
FORCEPROP 1 LAST OFFPAGE TRUE
J 0
(-425 -775);
DISPLAY 0.872340 (-425 -775);
PAINT GREEN (-425 -775);
DISPLAY INVISIBLE (-425 -775);
FORCEPROP 1 LAST COMMENT_BODY TRUE
J 0
(-795 -745);
DISPLAY 0.872340 (-795 -745);
PAINT GREEN (-795 -745);
DISPLAY INVISIBLE (-795 -745);
FORCEPROP 2 LAST PATH I167
J 0
(-550 -600);
DISPLAY 1.021277 (-550 -600);
DISPLAY INVISIBLE (-550 -600);
FORCEADD OFFPAGE..2
(-750 -775);
FORCEPROP 2 LAST $XR1 44 
J 0
(-441 -775);
DISPLAY 0.638298 (-441 -775);
PAINT MONO (-441 -775);
FORCEPROP 2 LAST $XR0 119 
J 0
(-561 -775);
DISPLAY 0.638298 (-561 -775);
PAINT MONO (-561 -775);
FORCEPROP 2 LAST CDS_LIB standard
J 0
(-750 -775);
DISPLAY INVISIBLE (-750 -775);
FORCEPROP 1 LAST OFFPAGE TRUE
J 0
(-425 -900);
DISPLAY 0.872340 (-425 -900);
PAINT GREEN (-425 -900);
DISPLAY INVISIBLE (-425 -900);
FORCEPROP 1 LAST COMMENT_BODY TRUE
J 0
(-795 -870);
DISPLAY 0.872340 (-795 -870);
PAINT GREEN (-795 -870);
DISPLAY INVISIBLE (-795 -870);
FORCEPROP 2 LAST PATH I168
J 0
(-550 -725);
DISPLAY 1.021277 (-550 -725);
DISPLAY INVISIBLE (-550 -725);
FORCEADD Q_RES..1
(-2100 -650);
FORCEPROP 1 LAST PART_NUMBER CS12402FB01
J 0
(-2200 -600);
DISPLAY 0.510638 (-2200 -600);
DISPLAY INVISIBLE (-2200 -600);
FORCEPROP 1 LAST TOLERANCE 1%
J 0
(-1875 -650);
DISPLAY 0.638298 (-1875 -650);
FORCEPROP 1 LAST MATERIAL EMPTY
J 0
(-1775 -650);
DISPLAY 0.638298 (-1775 -650);
PAINT RED (-1775 -650);
FORCEPROP 1 LAST VALUE 240
J 2
(-1900 -650);
DISPLAY 0.638298 (-1900 -650);
FORCEPROP 1 LAST $LOCATION R1229
J 0
(-2325 -650);
DISPLAY 0.787234 (-2325 -650);
FORCEPROP 1 LASTPIN (-2200 -650) $PN 1
J 0
(-2188 -638);
DISPLAY 0.787234 (-2188 -638);
FORCEPROP 1 LASTPIN (-2000 -650) $PN 2
J 0
(-2038 -638);
DISPLAY 0.787234 (-2038 -638);
FORCEPROP 1 LAST PACK_TYPE 0402LF
J 0
(-2200 -575);
DISPLAY 0.510638 (-2200 -575);
DISPLAY INVISIBLE (-2200 -575);
FORCEPROP 1 LAST WATTAGE 1/16W
J 2
(-1925 -575);
DISPLAY 0.510638 (-1925 -575);
DISPLAY INVISIBLE (-1925 -575);
FORCEPROP 2 LAST CDS_LIB pure_quanta
J 0
(-2100 -650);
PAINT MONO (-2100 -650);
DISPLAY INVISIBLE (-2100 -650);
FORCEPROP 1 LAST PATH I169
J 0
(-2150 -500);
DISPLAY 0.978723 (-2150 -500);
PAINT WHITE (-2150 -500);
DISPLAY INVISIBLE (-2150 -500);
FORCEPROP 2 LAST CDS_LOCATION R1229
J 0
(-2150 -450);
DISPLAY 1.021277 (-2150 -450);
DISPLAY INVISIBLE (-2150 -450);
FORCEPROP 2 LAST $SEC 1
J 0
(-2150 -450);
DISPLAY 0.680851 (-2150 -450);
PAINT MONO (-2150 -450);
DISPLAY INVISIBLE (-2150 -450);
FORCEPROP 2 LAST CDS_SEC 1
J 0
(-2150 -450);
DISPLAY 1.021277 (-2150 -450);
DISPLAY INVISIBLE (-2150 -450);
FORCEADD Q_RES..1
(-2100 -775);
FORCEPROP 1 LAST PART_NUMBER CS12402FB01
J 0
(-2200 -725);
DISPLAY 0.510638 (-2200 -725);
DISPLAY INVISIBLE (-2200 -725);
FORCEPROP 1 LAST TOLERANCE 1%
J 0
(-1875 -775);
DISPLAY 0.638298 (-1875 -775);
FORCEPROP 1 LAST MATERIAL EMPTY
J 0
(-1775 -775);
DISPLAY 0.638298 (-1775 -775);
PAINT RED (-1775 -775);
FORCEPROP 1 LAST VALUE 240
J 2
(-1900 -775);
DISPLAY 0.638298 (-1900 -775);
FORCEPROP 1 LAST $LOCATION R1230
J 0
(-2325 -775);
DISPLAY 0.787234 (-2325 -775);
FORCEPROP 1 LASTPIN (-2200 -775) $PN 1
J 0
(-2188 -763);
DISPLAY 0.787234 (-2188 -763);
FORCEPROP 1 LASTPIN (-2000 -775) $PN 2
J 0
(-2038 -763);
DISPLAY 0.787234 (-2038 -763);
FORCEPROP 1 LAST PACK_TYPE 0402LF
J 0
(-2200 -700);
DISPLAY 0.510638 (-2200 -700);
DISPLAY INVISIBLE (-2200 -700);
FORCEPROP 1 LAST WATTAGE 1/16W
J 2
(-1925 -700);
DISPLAY 0.510638 (-1925 -700);
DISPLAY INVISIBLE (-1925 -700);
FORCEPROP 2 LAST CDS_LIB pure_quanta
J 0
(-2100 -775);
PAINT MONO (-2100 -775);
DISPLAY INVISIBLE (-2100 -775);
FORCEPROP 1 LAST PATH I170
J 0
(-2150 -625);
DISPLAY 0.978723 (-2150 -625);
PAINT WHITE (-2150 -625);
DISPLAY INVISIBLE (-2150 -625);
FORCEPROP 2 LAST CDS_LOCATION R1230
J 0
(-2150 -575);
DISPLAY 1.021277 (-2150 -575);
DISPLAY INVISIBLE (-2150 -575);
FORCEPROP 2 LAST $SEC 1
J 0
(-2150 -575);
DISPLAY 0.680851 (-2150 -575);
PAINT MONO (-2150 -575);
DISPLAY INVISIBLE (-2150 -575);
FORCEPROP 2 LAST CDS_SEC 1
J 0
(-2150 -575);
DISPLAY 1.021277 (-2150 -575);
DISPLAY INVISIBLE (-2150 -575);
FORCEADD UNIVERSAL_GND..1
(-75 -275);
FORCEPROP 3 LASTPIN (-75 -225) SIG_NAME GND\g
J 0
(-65 -215);
DISPLAY 0.659574 (-65 -215);
PAINT MONO (-65 -215);
DISPLAY INVISIBLE (-65 -215);
FORCEPROP 2 LAST CDS_LIB logical_power
J 0
(-75 -275);
DISPLAY INVISIBLE (-75 -275);
FORCEPROP 1 LAST HDL_POWER GND
J 1
(-50 -350);
DISPLAY 0.872340 (-50 -350);
PAINT GREEN (-50 -350);
DISPLAY INVISIBLE (-50 -350);
FORCEPROP 1 LAST PATH I171
J 0
(0 -275);
DISPLAY 0.872340 (0 -275);
PAINT AQUA (0 -275);
DISPLAY INVISIBLE (0 -275);
FORCEADD Q_RES..1
(250 125);
FORCEPROP 1 LAST PART_NUMBER CS12402FB01
J 0
(150 175);
DISPLAY 0.510638 (150 175);
DISPLAY INVISIBLE (150 175);
FORCEPROP 1 LAST MATERIAL EMPTY
J 0
(575 125);
DISPLAY 0.638298 (575 125);
PAINT RED (575 125);
FORCEPROP 1 LAST TOLERANCE 1%
J 0
(475 125);
DISPLAY 0.638298 (475 125);
FORCEPROP 1 LAST VALUE 240
J 2
(450 125);
DISPLAY 0.638298 (450 125);
FORCEPROP 1 LAST $LOCATION R3024
J 0
(25 125);
DISPLAY 0.787234 (25 125);
FORCEPROP 1 LASTPIN (150 125) $PN 1
J 0
(162 137);
DISPLAY 0.787234 (162 137);
FORCEPROP 1 LASTPIN (350 125) $PN 2
J 0
(312 137);
DISPLAY 0.787234 (312 137);
FORCEPROP 2 LAST CDS_LIB pure_quanta
J 0
(250 125);
PAINT MONO (250 125);
DISPLAY INVISIBLE (250 125);
FORCEPROP 1 LAST WATTAGE 1/16W
J 2
(425 200);
DISPLAY 0.510638 (425 200);
DISPLAY INVISIBLE (425 200);
FORCEPROP 1 LAST PACK_TYPE 0402LF
J 0
(150 200);
DISPLAY 0.510638 (150 200);
DISPLAY INVISIBLE (150 200);
FORCEPROP 1 LAST PATH I172
J 0
(200 275);
DISPLAY 0.978723 (200 275);
PAINT WHITE (200 275);
DISPLAY INVISIBLE (200 275);
FORCEPROP 2 LAST CDS_LOCATION R3024
J 0
(200 325);
DISPLAY 1.021277 (200 325);
DISPLAY INVISIBLE (200 325);
FORCEPROP 2 LAST $SEC 1
J 0
(200 325);
DISPLAY 0.680851 (200 325);
PAINT MONO (200 325);
DISPLAY INVISIBLE (200 325);
FORCEPROP 2 LAST CDS_SEC 1
J 0
(200 325);
DISPLAY 1.021277 (200 325);
DISPLAY INVISIBLE (200 325);
FORCEADD OFFPAGE..2
(1650 -125);
FORCEPROP 2 LAST $XR1 44 
J 0
(1959 -125);
DISPLAY 0.638298 (1959 -125);
PAINT MONO (1959 -125);
FORCEPROP 2 LAST $XR0 119 
J 0
(1839 -125);
DISPLAY 0.638298 (1839 -125);
PAINT MONO (1839 -125);
FORCEPROP 2 LAST CDS_LIB standard
J 0
(1650 -125);
DISPLAY INVISIBLE (1650 -125);
FORCEPROP 1 LAST OFFPAGE TRUE
J 0
(1975 -250);
DISPLAY 0.872340 (1975 -250);
PAINT GREEN (1975 -250);
DISPLAY INVISIBLE (1975 -250);
FORCEPROP 1 LAST COMMENT_BODY TRUE
J 0
(1605 -220);
DISPLAY 0.872340 (1605 -220);
PAINT GREEN (1605 -220);
DISPLAY INVISIBLE (1605 -220);
FORCEPROP 2 LAST PATH I173
J 0
(1850 -75);
DISPLAY 1.021277 (1850 -75);
DISPLAY INVISIBLE (1850 -75);
FORCEADD OFFPAGE..2
(1650 0);
FORCEPROP 2 LAST $XR1 44 
J 0
(1959 0);
DISPLAY 0.638298 (1959 0);
PAINT MONO (1959 0);
FORCEPROP 2 LAST $XR0 119 
J 0
(1839 0);
DISPLAY 0.638298 (1839 0);
PAINT MONO (1839 0);
FORCEPROP 2 LAST CDS_LIB standard
J 0
(1650 0);
DISPLAY INVISIBLE (1650 0);
FORCEPROP 1 LAST OFFPAGE TRUE
J 0
(1975 -125);
DISPLAY 0.872340 (1975 -125);
PAINT GREEN (1975 -125);
DISPLAY INVISIBLE (1975 -125);
FORCEPROP 1 LAST COMMENT_BODY TRUE
J 0
(1605 -95);
DISPLAY 0.872340 (1605 -95);
PAINT GREEN (1605 -95);
DISPLAY INVISIBLE (1605 -95);
FORCEPROP 2 LAST PATH I174
J 0
(1850 50);
DISPLAY 1.021277 (1850 50);
DISPLAY INVISIBLE (1850 50);
FORCEADD OFFPAGE..2
(1650 125);
FORCEPROP 2 LAST $XR0 44 
J 0
(1839 125);
DISPLAY 0.638298 (1839 125);
PAINT MONO (1839 125);
FORCEPROP 2 LAST CDS_LIB standard
J 0
(1650 125);
DISPLAY INVISIBLE (1650 125);
FORCEPROP 1 LAST OFFPAGE TRUE
J 0
(1975 0);
DISPLAY 0.872340 (1975 0);
PAINT GREEN (1975 0);
DISPLAY INVISIBLE (1975 0);
FORCEPROP 1 LAST COMMENT_BODY TRUE
J 0
(1605 30);
DISPLAY 0.872340 (1605 30);
PAINT GREEN (1605 30);
DISPLAY INVISIBLE (1605 30);
FORCEPROP 2 LAST PATH I175
J 0
(1850 175);
DISPLAY 1.021277 (1850 175);
DISPLAY INVISIBLE (1850 175);
FORCEADD Q_RES..1
(250 0);
FORCEPROP 1 LAST PART_NUMBER CS12402FB01
J 0
(150 50);
DISPLAY 0.510638 (150 50);
DISPLAY INVISIBLE (150 50);
FORCEPROP 1 LAST VALUE 240
J 2
(450 0);
DISPLAY 0.638298 (450 0);
FORCEPROP 1 LAST MATERIAL EMPTY
J 0
(575 0);
DISPLAY 0.638298 (575 0);
PAINT RED (575 0);
FORCEPROP 1 LAST TOLERANCE 1%
J 0
(475 0);
DISPLAY 0.638298 (475 0);
FORCEPROP 1 LAST $LOCATION R1235
J 0
(25 0);
DISPLAY 0.787234 (25 0);
FORCEPROP 1 LASTPIN (150 0) $PN 1
J 0
(162 12);
DISPLAY 0.787234 (162 12);
FORCEPROP 1 LASTPIN (350 0) $PN 2
J 0
(312 12);
DISPLAY 0.787234 (312 12);
FORCEPROP 1 LAST PACK_TYPE 0402LF
J 0
(150 75);
DISPLAY 0.510638 (150 75);
DISPLAY INVISIBLE (150 75);
FORCEPROP 1 LAST WATTAGE 1/16W
J 2
(425 75);
DISPLAY 0.510638 (425 75);
DISPLAY INVISIBLE (425 75);
FORCEPROP 2 LAST CDS_LIB pure_quanta
J 0
(250 0);
PAINT MONO (250 0);
DISPLAY INVISIBLE (250 0);
FORCEPROP 1 LAST PATH I176
J 0
(200 150);
DISPLAY 0.978723 (200 150);
PAINT WHITE (200 150);
DISPLAY INVISIBLE (200 150);
FORCEPROP 2 LAST CDS_LOCATION R1235
J 0
(200 200);
DISPLAY 1.021277 (200 200);
DISPLAY INVISIBLE (200 200);
FORCEPROP 2 LAST $SEC 1
J 0
(200 200);
DISPLAY 0.680851 (200 200);
PAINT MONO (200 200);
DISPLAY INVISIBLE (200 200);
FORCEPROP 2 LAST CDS_SEC 1
J 0
(200 200);
DISPLAY 1.021277 (200 200);
DISPLAY INVISIBLE (200 200);
FORCEADD Q_RES..1
(250 -125);
FORCEPROP 1 LAST PART_NUMBER CS12402FB01
J 0
(150 -75);
DISPLAY 0.510638 (150 -75);
DISPLAY INVISIBLE (150 -75);
FORCEPROP 1 LAST TOLERANCE 1%
J 0
(475 -125);
DISPLAY 0.638298 (475 -125);
FORCEPROP 1 LAST VALUE 240
J 2
(450 -125);
DISPLAY 0.638298 (450 -125);
FORCEPROP 1 LAST MATERIAL EMPTY
J 0
(575 -125);
DISPLAY 0.638298 (575 -125);
PAINT RED (575 -125);
FORCEPROP 1 LAST $LOCATION R1236
J 0
(25 -125);
DISPLAY 0.787234 (25 -125);
FORCEPROP 1 LASTPIN (150 -125) $PN 1
J 0
(162 -113);
DISPLAY 0.787234 (162 -113);
FORCEPROP 1 LASTPIN (350 -125) $PN 2
J 0
(312 -113);
DISPLAY 0.787234 (312 -113);
FORCEPROP 1 LAST PACK_TYPE 0402LF
J 0
(150 -50);
DISPLAY 0.510638 (150 -50);
DISPLAY INVISIBLE (150 -50);
FORCEPROP 1 LAST WATTAGE 1/16W
J 2
(425 -50);
DISPLAY 0.510638 (425 -50);
DISPLAY INVISIBLE (425 -50);
FORCEPROP 2 LAST CDS_LIB pure_quanta
J 0
(250 -125);
PAINT MONO (250 -125);
DISPLAY INVISIBLE (250 -125);
FORCEPROP 1 LAST PATH I177
J 0
(200 25);
DISPLAY 0.978723 (200 25);
PAINT WHITE (200 25);
DISPLAY INVISIBLE (200 25);
FORCEPROP 2 LAST CDS_LOCATION R1236
J 0
(200 75);
DISPLAY 1.021277 (200 75);
DISPLAY INVISIBLE (200 75);
FORCEPROP 2 LAST $SEC 1
J 0
(200 75);
DISPLAY 0.680851 (200 75);
PAINT MONO (200 75);
DISPLAY INVISIBLE (200 75);
FORCEPROP 2 LAST CDS_SEC 1
J 0
(200 75);
DISPLAY 1.021277 (200 75);
DISPLAY INVISIBLE (200 75);
FORCEADD OFFPAGE..2
(-750 -1225);
FORCEPROP 2 LAST $XR0 45 
J 0
(-561 -1225);
DISPLAY 0.638298 (-561 -1225);
PAINT MONO (-561 -1225);
FORCEPROP 2 LAST CDS_LIB standard
J 0
(-750 -1225);
PAINT MONO (-750 -1225);
DISPLAY INVISIBLE (-750 -1225);
FORCEPROP 1 LAST OFFPAGE TRUE
J 0
(-425 -1350);
DISPLAY 0.872340 (-425 -1350);
PAINT GREEN (-425 -1350);
DISPLAY INVISIBLE (-425 -1350);
FORCEPROP 1 LAST COMMENT_BODY TRUE
J 0
(-795 -1320);
DISPLAY 0.872340 (-795 -1320);
PAINT GREEN (-795 -1320);
DISPLAY INVISIBLE (-795 -1320);
FORCEPROP 2 LAST PATH I178
J 0
(-550 -1175);
DISPLAY 1.021277 (-550 -1175);
DISPLAY INVISIBLE (-550 -1175);
FORCEADD UNIVERSAL_POWER..1
(-2375 3825);
FORCEPROP 3 LASTPIN (-2375 3775) SIG_NAME PVNN_TERM_CPU0\g
J 0
(-2365 3785);
DISPLAY 0.659574 (-2365 3785);
PAINT MONO (-2365 3785);
DISPLAY INVISIBLE (-2365 3785);
FORCEPROP 1 LAST HDL_POWER PVNN_TERM_CPU0
J 1
(-2375 3875);
DISPLAY 0.872340 (-2375 3875);
PAINT GREEN (-2375 3875);
FORCEPROP 2 LAST CDS_LIB logical_power
J 0
(-2375 3825);
DISPLAY INVISIBLE (-2375 3825);
FORCEPROP 1 LAST PATH I18
J 0
(-2325 3850);
DISPLAY 0.872340 (-2325 3850);
PAINT AQUA (-2325 3850);
DISPLAY INVISIBLE (-2325 3850);
FORCEADD Q_RES..1
R 5
(2975 3375);
FORCEPROP 1 LAST PART_NUMBER CS12402FB01
J 0
(2650 3425);
DISPLAY 0.510638 (2650 3425);
DISPLAY INVISIBLE (2650 3425);
FORCEPROP 1 LAST PACK_TYPE 0402LF
J 0
(2775 3400);
DISPLAY 0.510638 (2775 3400);
FORCEPROP 1 LAST WATTAGE 1/16W
J 2
(2900 3375);
DISPLAY 0.510638 (2900 3375);
FORCEPROP 1 LAST VALUE 240
J 2
(2900 3350);
DISPLAY 0.404255 (2900 3350);
FORCEPROP 1 LAST TOLERANCE 1%
J 0
(2850 3325);
DISPLAY 0.404255 (2850 3325);
FORCEPROP 1 LAST MATERIAL EMPTY
J 0
(2800 3300);
DISPLAY 0.404255 (2800 3300);
PAINT RED (2800 3300);
FORCEPROP 1 LAST $LOCATION R292
J 0
(2800 3450);
DISPLAY 0.638298 (2800 3450);
FORCEPROP 1 LASTPIN (2975 3475) $PN 1
J 0
(2987 3463);
DISPLAY 0.787234 (2987 3463);
FORCEPROP 1 LASTPIN (2975 3275) $PN 2
J 0
(2990 3260);
DISPLAY 0.787234 (2990 3260);
FORCEPROP 2 LAST CDS_LIB pure_quanta
R 3
J 0
(2975 3375);
PAINT MONO (2975 3375);
DISPLAY INVISIBLE (2975 3375);
FORCEPROP 1 LAST PATH I196
R 3
J 0
(3125 3425);
DISPLAY 0.978723 (3125 3425);
PAINT WHITE (3125 3425);
DISPLAY INVISIBLE (3125 3425);
FORCEPROP 2 LAST CDS_LOCATION R292
R 3
J 0
(3175 3425);
DISPLAY 1.021277 (3175 3425);
DISPLAY INVISIBLE (3175 3425);
FORCEPROP 2 LAST $SEC 1
R 3
J 0
(3175 3425);
DISPLAY 0.680851 (3175 3425);
PAINT MONO (3175 3425);
DISPLAY INVISIBLE (3175 3425);
FORCEPROP 2 LAST CDS_SEC 1
R 3
J 0
(3175 3425);
DISPLAY 1.021277 (3175 3425);
DISPLAY INVISIBLE (3175 3425);
FORCEADD UNIVERSAL_GND..1
(2975 2800);
FORCEPROP 3 LASTPIN (2975 2850) SIG_NAME GND\g
J 0
(2985 2860);
DISPLAY 0.659574 (2985 2860);
PAINT MONO (2985 2860);
DISPLAY INVISIBLE (2985 2860);
FORCEPROP 2 LAST CDS_LIB logical_power
J 0
(2975 2800);
DISPLAY INVISIBLE (2975 2800);
FORCEPROP 1 LAST HDL_POWER GND
J 1
(3000 2725);
DISPLAY 0.872340 (3000 2725);
PAINT GREEN (3000 2725);
DISPLAY INVISIBLE (3000 2725);
FORCEPROP 1 LAST PATH I197
J 0
(3050 2800);
DISPLAY 0.872340 (3050 2800);
PAINT AQUA (3050 2800);
DISPLAY INVISIBLE (3050 2800);
FORCEADD OFFPAGE..2
(6000 3200);
FORCEPROP 2 LAST $XR0 13 
J 0
(6189 3200);
DISPLAY 0.638298 (6189 3200);
PAINT MONO (6189 3200);
FORCEPROP 2 LAST CDS_LIB standard
J 0
(6000 3200);
DISPLAY INVISIBLE (6000 3200);
FORCEPROP 1 LAST OFFPAGE TRUE
J 0
(6325 3075);
DISPLAY 0.872340 (6325 3075);
PAINT GREEN (6325 3075);
DISPLAY INVISIBLE (6325 3075);
FORCEPROP 1 LAST COMMENT_BODY TRUE
J 0
(5955 3105);
DISPLAY 0.872340 (5955 3105);
PAINT GREEN (5955 3105);
DISPLAY INVISIBLE (5955 3105);
FORCEPROP 2 LAST PATH I199
J 0
(6200 3250);
DISPLAY 1.021277 (6200 3250);
DISPLAY INVISIBLE (6200 3250);
FORCEADD UNIVERSAL_POWER..1
(2975 3675);
FORCEPROP 3 LASTPIN (2975 3625) SIG_NAME PVNN_TERM_CPU0\g
J 0
(2985 3635);
DISPLAY 0.659574 (2985 3635);
PAINT MONO (2985 3635);
DISPLAY INVISIBLE (2985 3635);
FORCEPROP 1 LAST HDL_POWER PVNN_TERM_CPU0
J 1
(2975 3725);
DISPLAY 0.872340 (2975 3725);
PAINT GREEN (2975 3725);
FORCEPROP 2 LAST CDS_LIB logical_power
J 0
(2975 3675);
DISPLAY INVISIBLE (2975 3675);
FORCEPROP 1 LAST PATH I210
J 0
(3025 3700);
DISPLAY 0.872340 (3025 3700);
PAINT AQUA (3025 3700);
DISPLAY INVISIBLE (3025 3700);
FORCEADD Q_RES..1
R 5
(2975 3050);
FORCEPROP 1 LAST PART_NUMBER CS12402FB01
J 0
(2650 3100);
DISPLAY 0.510638 (2650 3100);
DISPLAY INVISIBLE (2650 3100);
FORCEPROP 1 LAST TOLERANCE 1%
J 0
(2850 3000);
DISPLAY 0.404255 (2850 3000);
FORCEPROP 1 LAST VALUE 240
J 2
(2900 3025);
DISPLAY 0.404255 (2900 3025);
FORCEPROP 1 LAST PACK_TYPE 0402LF
J 0
(2775 3075);
DISPLAY 0.510638 (2775 3075);
FORCEPROP 1 LAST WATTAGE 1/16W
J 2
(2900 3050);
DISPLAY 0.510638 (2900 3050);
FORCEPROP 1 LAST MATERIAL EMPTY
J 0
(2800 2975);
DISPLAY 0.404255 (2800 2975);
PAINT RED (2800 2975);
FORCEPROP 1 LAST LOCATION R293
J 0
(2800 3125);
DISPLAY 0.638298 (2800 3125);
FORCEPROP 1 LASTPIN (2975 3150) $PN 1
J 0
(2987 3138);
DISPLAY 0.787234 (2987 3138);
FORCEPROP 1 LASTPIN (2975 2950) $PN 2
J 0
(2990 2935);
DISPLAY 0.787234 (2990 2935);
FORCEPROP 2 LAST CDS_LIB pure_quanta
R 3
J 0
(2975 3050);
PAINT MONO (2975 3050);
DISPLAY INVISIBLE (2975 3050);
FORCEPROP 1 LAST PATH I211
R 3
J 0
(3125 3100);
DISPLAY 0.978723 (3125 3100);
PAINT WHITE (3125 3100);
DISPLAY INVISIBLE (3125 3100);
FORCEPROP 2 LAST $SEC 1
R 3
J 0
(3175 3100);
DISPLAY 0.680851 (3175 3100);
PAINT MONO (3175 3100);
DISPLAY INVISIBLE (3175 3100);
FORCEPROP 2 LAST CDS_SEC 1
R 3
J 0
(3175 3100);
DISPLAY 1.021277 (3175 3100);
DISPLAY INVISIBLE (3175 3100);
FORCEADD OFFPAGE..2
(3950 3225);
FORCEPROP 2 LAST $XR0 13 
J 0
(4139 3225);
DISPLAY 0.638298 (4139 3225);
PAINT MONO (4139 3225);
FORCEPROP 2 LAST CDS_LIB standard
J 0
(3950 3225);
DISPLAY INVISIBLE (3950 3225);
FORCEPROP 1 LAST OFFPAGE TRUE
J 0
(4275 3100);
DISPLAY 0.872340 (4275 3100);
PAINT GREEN (4275 3100);
DISPLAY INVISIBLE (4275 3100);
FORCEPROP 1 LAST COMMENT_BODY TRUE
J 0
(3905 3130);
DISPLAY 0.872340 (3905 3130);
PAINT GREEN (3905 3130);
DISPLAY INVISIBLE (3905 3130);
FORCEPROP 2 LAST PATH I212
J 2
(4150 3275);
DISPLAY 1.021277 (4150 3275);
DISPLAY INVISIBLE (4150 3275);
FORCEADD UNIVERSAL_GND..1
(5075 2775);
FORCEPROP 3 LASTPIN (5075 2825) SIG_NAME GND\g
J 0
(5085 2835);
DISPLAY 0.659574 (5085 2835);
PAINT MONO (5085 2835);
DISPLAY INVISIBLE (5085 2835);
FORCEPROP 2 LAST CDS_LIB logical_power
J 0
(5075 2775);
DISPLAY INVISIBLE (5075 2775);
FORCEPROP 1 LAST HDL_POWER GND
J 1
(5100 2700);
DISPLAY 0.872340 (5100 2700);
PAINT GREEN (5100 2700);
DISPLAY INVISIBLE (5100 2700);
FORCEPROP 1 LAST PATH I213
J 0
(5150 2775);
DISPLAY 0.872340 (5150 2775);
PAINT AQUA (5150 2775);
DISPLAY INVISIBLE (5150 2775);
FORCEADD UNIVERSAL_POWER..1
(5075 3650);
FORCEPROP 3 LASTPIN (5075 3600) SIG_NAME PVNN_TERM_CPU0\g
J 0
(5085 3610);
DISPLAY 0.659574 (5085 3610);
PAINT MONO (5085 3610);
DISPLAY INVISIBLE (5085 3610);
FORCEPROP 1 LAST HDL_POWER PVNN_TERM_CPU0
J 1
(5075 3700);
DISPLAY 0.872340 (5075 3700);
PAINT GREEN (5075 3700);
FORCEPROP 2 LAST CDS_LIB logical_power
J 0
(5075 3650);
DISPLAY INVISIBLE (5075 3650);
FORCEPROP 1 LAST PATH I214
J 0
(5125 3675);
DISPLAY 0.872340 (5125 3675);
PAINT AQUA (5125 3675);
DISPLAY INVISIBLE (5125 3675);
FORCEADD Q_RES..1
R 5
(5075 3350);
FORCEPROP 1 LAST PART_NUMBER CS12402FB01
J 0
(4750 3400);
DISPLAY 0.510638 (4750 3400);
DISPLAY INVISIBLE (4750 3400);
FORCEPROP 1 LAST TOLERANCE 1%
J 0
(4950 3300);
DISPLAY 0.404255 (4950 3300);
FORCEPROP 1 LAST VALUE 240
J 2
(5000 3325);
DISPLAY 0.404255 (5000 3325);
FORCEPROP 1 LAST PACK_TYPE 0402LF
J 0
(4875 3375);
DISPLAY 0.510638 (4875 3375);
FORCEPROP 1 LAST WATTAGE 1/16W
J 2
(5000 3350);
DISPLAY 0.510638 (5000 3350);
FORCEPROP 1 LAST MATERIAL EMPTY
J 0
(4900 3275);
DISPLAY 0.404255 (4900 3275);
FORCEPROP 1 LAST $LOCATION R4262
J 0
(4900 3425);
DISPLAY 0.638298 (4900 3425);
FORCEPROP 1 LASTPIN (5075 3450) $PN 1
J 0
(5087 3438);
DISPLAY 0.787234 (5087 3438);
FORCEPROP 1 LASTPIN (5075 3250) $PN 2
J 0
(5090 3235);
DISPLAY 0.787234 (5090 3235);
FORCEPROP 2 LAST CDS_LIB pure_quanta
R 3
J 0
(5075 3350);
PAINT MONO (5075 3350);
DISPLAY INVISIBLE (5075 3350);
FORCEPROP 1 LAST PATH I215
R 3
J 0
(5225 3400);
DISPLAY 0.978723 (5225 3400);
PAINT WHITE (5225 3400);
DISPLAY INVISIBLE (5225 3400);
FORCEPROP 2 LAST CDS_LOCATION R4262
R 3
J 0
(5275 3400);
DISPLAY 1.021277 (5275 3400);
DISPLAY INVISIBLE (5275 3400);
FORCEPROP 2 LAST $SEC 1
R 3
J 0
(5275 3400);
DISPLAY 0.680851 (5275 3400);
PAINT MONO (5275 3400);
DISPLAY INVISIBLE (5275 3400);
FORCEPROP 2 LAST CDS_SEC 1
R 3
J 0
(5275 3400);
DISPLAY 1.021277 (5275 3400);
DISPLAY INVISIBLE (5275 3400);
FORCEADD Q_RES..1
R 5
(5075 3025);
FORCEPROP 1 LAST PART_NUMBER CS12402FB01
J 0
(4750 3075);
DISPLAY 0.510638 (4750 3075);
DISPLAY INVISIBLE (4750 3075);
FORCEPROP 1 LAST VALUE 240
J 2
(5000 3000);
DISPLAY 0.404255 (5000 3000);
FORCEPROP 1 LAST TOLERANCE 1%
J 0
(4950 2975);
DISPLAY 0.404255 (4950 2975);
FORCEPROP 1 LAST WATTAGE 1/16W
J 2
(5000 3025);
DISPLAY 0.510638 (5000 3025);
FORCEPROP 1 LAST PACK_TYPE 0402LF
J 0
(4875 3050);
DISPLAY 0.510638 (4875 3050);
FORCEPROP 1 LAST MATERIAL EMPTY
J 0
(4900 2950);
DISPLAY 0.404255 (4900 2950);
PAINT RED (4900 2950);
FORCEPROP 1 LAST $LOCATION R4263
J 0
(4900 3100);
DISPLAY 0.638298 (4900 3100);
FORCEPROP 1 LASTPIN (5075 3125) $PN 1
J 0
(5087 3113);
DISPLAY 0.787234 (5087 3113);
FORCEPROP 1 LASTPIN (5075 2925) $PN 2
J 0
(5090 2910);
DISPLAY 0.787234 (5090 2910);
FORCEPROP 2 LAST CDS_LIB pure_quanta
R 3
J 0
(5075 3025);
PAINT MONO (5075 3025);
DISPLAY INVISIBLE (5075 3025);
FORCEPROP 1 LAST PATH I216
R 3
J 0
(5225 3075);
DISPLAY 0.978723 (5225 3075);
PAINT WHITE (5225 3075);
DISPLAY INVISIBLE (5225 3075);
FORCEPROP 2 LAST CDS_LOCATION R4263
R 3
J 0
(5275 3075);
DISPLAY 1.021277 (5275 3075);
DISPLAY INVISIBLE (5275 3075);
FORCEPROP 2 LAST $SEC 1
R 3
J 0
(5275 3075);
DISPLAY 0.680851 (5275 3075);
PAINT MONO (5275 3075);
DISPLAY INVISIBLE (5275 3075);
FORCEPROP 2 LAST CDS_SEC 1
R 3
J 0
(5275 3075);
DISPLAY 1.021277 (5275 3075);
DISPLAY INVISIBLE (5275 3075);
FORCEADD OFFPAGE..2
(5975 -1100);
FORCEPROP 2 LAST $XR0 44 
J 0
(6164 -1100);
DISPLAY 0.638298 (6164 -1100);
PAINT MONO (6164 -1100);
FORCEPROP 2 LAST CDS_LIB standard
J 0
(5975 -1100);
DISPLAY INVISIBLE (5975 -1100);
FORCEPROP 1 LAST OFFPAGE TRUE
J 0
(6300 -1225);
DISPLAY 0.872340 (6300 -1225);
PAINT GREEN (6300 -1225);
DISPLAY INVISIBLE (6300 -1225);
FORCEPROP 1 LAST COMMENT_BODY TRUE
J 0
(5930 -1195);
DISPLAY 0.872340 (5930 -1195);
PAINT GREEN (5930 -1195);
DISPLAY INVISIBLE (5930 -1195);
FORCEPROP 2 LAST PATH I217
J 0
(6200 -1050);
DISPLAY 1.021277 (6200 -1050);
DISPLAY INVISIBLE (6200 -1050);
FORCEADD UNIVERSAL_POWER..1
(5050 -650);
FORCEPROP 3 LASTPIN (5050 -700) SIG_NAME PVNN_TERM_CPU0\g
J 0
(5060 -690);
DISPLAY 0.659574 (5060 -690);
PAINT MONO (5060 -690);
DISPLAY INVISIBLE (5060 -690);
FORCEPROP 1 LAST HDL_POWER PVNN_TERM_CPU0
J 1
(5050 -600);
DISPLAY 0.872340 (5050 -600);
PAINT GREEN (5050 -600);
FORCEPROP 2 LAST CDS_LIB logical_power
J 0
(5050 -650);
DISPLAY INVISIBLE (5050 -650);
FORCEPROP 1 LAST PATH I218
J 0
(5100 -625);
DISPLAY 0.872340 (5100 -625);
PAINT AQUA (5100 -625);
DISPLAY INVISIBLE (5100 -625);
FORCEADD Q_RES..1
R 5
(5050 -950);
FORCEPROP 1 LAST PART_NUMBER CS12402FB01
J 0
(4725 -900);
DISPLAY 0.510638 (4725 -900);
DISPLAY INVISIBLE (4725 -900);
FORCEPROP 1 LAST PACK_TYPE 0402LF
J 0
(4850 -925);
DISPLAY 0.510638 (4850 -925);
FORCEPROP 1 LAST WATTAGE 1/16W
J 2
(4975 -950);
DISPLAY 0.510638 (4975 -950);
FORCEPROP 1 LAST TOLERANCE 1%
J 0
(4925 -1000);
DISPLAY 0.404255 (4925 -1000);
FORCEPROP 1 LAST VALUE 240
J 2
(4975 -975);
DISPLAY 0.404255 (4975 -975);
FORCEPROP 1 LAST MATERIAL EMPTY
J 0
(4875 -1025);
DISPLAY 0.404255 (4875 -1025);
FORCEPROP 1 LAST $LOCATION R4260
J 0
(4875 -875);
DISPLAY 0.638298 (4875 -875);
FORCEPROP 1 LASTPIN (5050 -850) $PN 1
J 0
(5062 -862);
DISPLAY 0.787234 (5062 -862);
FORCEPROP 1 LASTPIN (5050 -1050) $PN 2
J 0
(5065 -1065);
DISPLAY 0.787234 (5065 -1065);
FORCEPROP 2 LAST CDS_LIB pure_quanta
R 3
J 0
(5050 -950);
PAINT MONO (5050 -950);
DISPLAY INVISIBLE (5050 -950);
FORCEPROP 1 LAST PATH I219
R 3
J 0
(5200 -900);
DISPLAY 0.978723 (5200 -900);
PAINT WHITE (5200 -900);
DISPLAY INVISIBLE (5200 -900);
FORCEPROP 2 LAST CDS_LOCATION R4260
R 3
J 0
(5250 -900);
DISPLAY 1.021277 (5250 -900);
DISPLAY INVISIBLE (5250 -900);
FORCEPROP 2 LAST $SEC 1
R 3
J 0
(5250 -900);
DISPLAY 0.680851 (5250 -900);
PAINT MONO (5250 -900);
DISPLAY INVISIBLE (5250 -900);
FORCEPROP 2 LAST CDS_SEC 1
R 3
J 0
(5250 -900);
DISPLAY 1.021277 (5250 -900);
DISPLAY INVISIBLE (5250 -900);
FORCEADD Q_RES..1
R 5
(5050 -1275);
FORCEPROP 1 LAST PART_NUMBER CS12402FB01
J 0
(4725 -1225);
DISPLAY 0.510638 (4725 -1225);
DISPLAY INVISIBLE (4725 -1225);
FORCEPROP 1 LAST PACK_TYPE 0402LF
J 0
(4850 -1250);
DISPLAY 0.510638 (4850 -1250);
FORCEPROP 1 LAST MATERIAL EMPTY
J 0
(4875 -1350);
DISPLAY 0.404255 (4875 -1350);
PAINT RED (4875 -1350);
FORCEPROP 1 LAST TOLERANCE 1%
J 0
(4925 -1325);
DISPLAY 0.404255 (4925 -1325);
FORCEPROP 1 LAST VALUE 240
J 2
(4975 -1300);
DISPLAY 0.404255 (4975 -1300);
FORCEPROP 1 LAST WATTAGE 1/16W
J 2
(4975 -1275);
DISPLAY 0.510638 (4975 -1275);
FORCEPROP 1 LAST $LOCATION R4261
J 0
(4875 -1200);
DISPLAY 0.638298 (4875 -1200);
FORCEPROP 1 LASTPIN (5050 -1175) $PN 1
J 0
(5062 -1187);
DISPLAY 0.787234 (5062 -1187);
FORCEPROP 1 LASTPIN (5050 -1375) $PN 2
J 0
(5065 -1390);
DISPLAY 0.787234 (5065 -1390);
FORCEPROP 2 LAST CDS_LIB pure_quanta
R 3
J 0
(5050 -1275);
PAINT MONO (5050 -1275);
DISPLAY INVISIBLE (5050 -1275);
FORCEPROP 1 LAST PATH I220
R 3
J 0
(5200 -1225);
DISPLAY 0.978723 (5200 -1225);
PAINT WHITE (5200 -1225);
DISPLAY INVISIBLE (5200 -1225);
FORCEPROP 2 LAST CDS_LOCATION R4261
R 3
J 0
(5250 -1225);
DISPLAY 1.021277 (5250 -1225);
DISPLAY INVISIBLE (5250 -1225);
FORCEPROP 2 LAST $SEC 1
R 3
J 0
(5250 -1225);
DISPLAY 0.680851 (5250 -1225);
PAINT MONO (5250 -1225);
DISPLAY INVISIBLE (5250 -1225);
FORCEPROP 2 LAST CDS_SEC 1
R 3
J 0
(5250 -1225);
DISPLAY 1.021277 (5250 -1225);
DISPLAY INVISIBLE (5250 -1225);
FORCEADD UNIVERSAL_GND..1
(5050 -1525);
FORCEPROP 3 LASTPIN (5050 -1475) SIG_NAME GND\g
J 0
(5060 -1465);
DISPLAY 0.659574 (5060 -1465);
PAINT MONO (5060 -1465);
DISPLAY INVISIBLE (5060 -1465);
FORCEPROP 2 LAST CDS_LIB logical_power
J 0
(5050 -1525);
DISPLAY INVISIBLE (5050 -1525);
FORCEPROP 1 LAST HDL_POWER GND
J 1
(5075 -1600);
DISPLAY 0.872340 (5075 -1600);
PAINT GREEN (5075 -1600);
DISPLAY INVISIBLE (5075 -1600);
FORCEPROP 1 LAST PATH I221
J 0
(5125 -1525);
DISPLAY 0.872340 (5125 -1525);
PAINT AQUA (5125 -1525);
DISPLAY INVISIBLE (5125 -1525);
FORCEADD OFFPAGE..2
(3925 -1075);
FORCEPROP 2 LAST $XR0 44 
J 0
(4114 -1075);
DISPLAY 0.638298 (4114 -1075);
PAINT MONO (4114 -1075);
FORCEPROP 2 LAST CDS_LIB standard
J 0
(3925 -1075);
DISPLAY INVISIBLE (3925 -1075);
FORCEPROP 1 LAST OFFPAGE TRUE
J 0
(4250 -1200);
DISPLAY 0.872340 (4250 -1200);
PAINT GREEN (4250 -1200);
DISPLAY INVISIBLE (4250 -1200);
FORCEPROP 1 LAST COMMENT_BODY TRUE
J 0
(3880 -1170);
DISPLAY 0.872340 (3880 -1170);
PAINT GREEN (3880 -1170);
DISPLAY INVISIBLE (3880 -1170);
FORCEPROP 2 LAST PATH I222
J 0
(4150 -1025);
DISPLAY 1.021277 (4150 -1025);
DISPLAY INVISIBLE (4150 -1025);
FORCEADD UNIVERSAL_POWER..1
(2950 -625);
FORCEPROP 3 LASTPIN (2950 -675) SIG_NAME PVNN_TERM_CPU0\g
J 0
(2960 -665);
DISPLAY 0.659574 (2960 -665);
PAINT MONO (2960 -665);
DISPLAY INVISIBLE (2960 -665);
FORCEPROP 1 LAST HDL_POWER PVNN_TERM_CPU0
J 1
(2950 -575);
DISPLAY 0.872340 (2950 -575);
PAINT GREEN (2950 -575);
FORCEPROP 2 LAST CDS_LIB logical_power
J 0
(2950 -625);
DISPLAY INVISIBLE (2950 -625);
FORCEPROP 1 LAST PATH I223
J 0
(3000 -600);
DISPLAY 0.872340 (3000 -600);
PAINT AQUA (3000 -600);
DISPLAY INVISIBLE (3000 -600);
FORCEADD Q_RES..1
R 5
(2950 -925);
FORCEPROP 1 LAST PART_NUMBER CS12402FB01
J 0
(2625 -875);
DISPLAY 0.510638 (2625 -875);
DISPLAY INVISIBLE (2625 -875);
FORCEPROP 1 LAST PACK_TYPE 0402LF
J 0
(2750 -900);
DISPLAY 0.510638 (2750 -900);
FORCEPROP 1 LAST TOLERANCE 1%
J 0
(2825 -975);
DISPLAY 0.404255 (2825 -975);
FORCEPROP 1 LAST MATERIAL EMPTY
J 0
(2775 -1000);
DISPLAY 0.404255 (2775 -1000);
FORCEPROP 1 LAST WATTAGE 1/16W
J 2
(2875 -925);
DISPLAY 0.510638 (2875 -925);
FORCEPROP 1 LAST VALUE 240
J 2
(2875 -950);
DISPLAY 0.404255 (2875 -950);
FORCEPROP 1 LAST LOCATION R288
J 0
(2775 -850);
DISPLAY 0.638298 (2775 -850);
FORCEPROP 1 LASTPIN (2950 -825) $PN 1
J 0
(2962 -837);
DISPLAY 0.787234 (2962 -837);
FORCEPROP 1 LASTPIN (2950 -1025) $PN 2
J 0
(2965 -1040);
DISPLAY 0.787234 (2965 -1040);
FORCEPROP 2 LAST CDS_LIB pure_quanta
R 3
J 0
(2950 -925);
PAINT MONO (2950 -925);
DISPLAY INVISIBLE (2950 -925);
FORCEPROP 1 LAST PATH I224
R 3
J 0
(3100 -875);
DISPLAY 0.978723 (3100 -875);
PAINT WHITE (3100 -875);
DISPLAY INVISIBLE (3100 -875);
FORCEPROP 2 LAST $SEC 1
R 3
J 0
(3150 -875);
DISPLAY 0.680851 (3150 -875);
PAINT MONO (3150 -875);
DISPLAY INVISIBLE (3150 -875);
FORCEPROP 2 LAST CDS_SEC 1
R 3
J 0
(3150 -875);
DISPLAY 1.021277 (3150 -875);
DISPLAY INVISIBLE (3150 -875);
FORCEADD Q_RES..1
R 5
(2950 -1250);
FORCEPROP 1 LAST PART_NUMBER CS12402FB01
J 0
(2625 -1200);
DISPLAY 0.510638 (2625 -1200);
DISPLAY INVISIBLE (2625 -1200);
FORCEPROP 1 LAST PACK_TYPE 0402LF
J 0
(2750 -1225);
DISPLAY 0.510638 (2750 -1225);
FORCEPROP 1 LAST WATTAGE 1/16W
J 2
(2875 -1250);
DISPLAY 0.510638 (2875 -1250);
FORCEPROP 1 LAST VALUE 240
J 2
(2875 -1275);
DISPLAY 0.404255 (2875 -1275);
FORCEPROP 1 LAST TOLERANCE 1%
J 0
(2825 -1300);
DISPLAY 0.404255 (2825 -1300);
FORCEPROP 1 LAST MATERIAL EMPTY
J 0
(2775 -1325);
DISPLAY 0.404255 (2775 -1325);
PAINT RED (2775 -1325);
FORCEPROP 1 LAST LOCATION R289
J 0
(2775 -1175);
DISPLAY 0.638298 (2775 -1175);
FORCEPROP 1 LASTPIN (2950 -1150) $PN 1
J 0
(2962 -1162);
DISPLAY 0.787234 (2962 -1162);
FORCEPROP 1 LASTPIN (2950 -1350) $PN 2
J 0
(2965 -1365);
DISPLAY 0.787234 (2965 -1365);
FORCEPROP 2 LAST CDS_LIB pure_quanta
R 3
J 0
(2950 -1250);
PAINT MONO (2950 -1250);
DISPLAY INVISIBLE (2950 -1250);
FORCEPROP 1 LAST PATH I225
R 3
J 0
(3100 -1200);
DISPLAY 0.978723 (3100 -1200);
PAINT WHITE (3100 -1200);
DISPLAY INVISIBLE (3100 -1200);
FORCEPROP 2 LAST $SEC 1
R 3
J 0
(3150 -1200);
DISPLAY 0.680851 (3150 -1200);
PAINT MONO (3150 -1200);
DISPLAY INVISIBLE (3150 -1200);
FORCEPROP 2 LAST CDS_SEC 1
R 3
J 0
(3150 -1200);
DISPLAY 1.021277 (3150 -1200);
DISPLAY INVISIBLE (3150 -1200);
FORCEADD UNIVERSAL_GND..1
(2950 -1500);
FORCEPROP 3 LASTPIN (2950 -1450) SIG_NAME GND\g
J 0
(2960 -1440);
DISPLAY 0.659574 (2960 -1440);
PAINT MONO (2960 -1440);
DISPLAY INVISIBLE (2960 -1440);
FORCEPROP 2 LAST CDS_LIB logical_power
J 0
(2950 -1500);
DISPLAY INVISIBLE (2950 -1500);
FORCEPROP 1 LAST HDL_POWER GND
J 1
(2975 -1575);
DISPLAY 0.872340 (2975 -1575);
PAINT GREEN (2975 -1575);
DISPLAY INVISIBLE (2975 -1575);
FORCEPROP 1 LAST PATH I226
J 0
(3025 -1500);
DISPLAY 0.872340 (3025 -1500);
PAINT AQUA (3025 -1500);
DISPLAY INVISIBLE (3025 -1500);
FORCEADD OFFPAGE..2
(-700 2700);
FORCEPROP 2 LAST $XR0 13 
J 0
(-511 2700);
DISPLAY 0.638298 (-511 2700);
PAINT MONO (-511 2700);
FORCEPROP 2 LAST CDS_LIB standard
J 0
(-700 2700);
DISPLAY INVISIBLE (-700 2700);
FORCEPROP 1 LAST OFFPAGE TRUE
J 0
(-375 2575);
DISPLAY 0.872340 (-375 2575);
PAINT GREEN (-375 2575);
DISPLAY INVISIBLE (-375 2575);
FORCEPROP 1 LAST COMMENT_BODY TRUE
J 0
(-745 2605);
DISPLAY 0.872340 (-745 2605);
PAINT GREEN (-745 2605);
DISPLAY INVISIBLE (-745 2605);
FORCEPROP 2 LAST PATH I29
J 0
(-500 2750);
DISPLAY 1.021277 (-500 2750);
DISPLAY INVISIBLE (-500 2750);
FORCEADD OFFPAGE..2
(-700 3075);
FORCEPROP 2 LAST $XR0 13 
J 0
(-511 3075);
DISPLAY 0.638298 (-511 3075);
PAINT MONO (-511 3075);
FORCEPROP 2 LAST CDS_LIB standard
J 0
(-700 3075);
DISPLAY INVISIBLE (-700 3075);
FORCEPROP 1 LAST OFFPAGE TRUE
J 0
(-375 2950);
DISPLAY 0.872340 (-375 2950);
PAINT GREEN (-375 2950);
DISPLAY INVISIBLE (-375 2950);
FORCEPROP 1 LAST COMMENT_BODY TRUE
J 0
(-745 2980);
DISPLAY 0.872340 (-745 2980);
PAINT GREEN (-745 2980);
DISPLAY INVISIBLE (-745 2980);
FORCEPROP 2 LAST PATH I40
J 0
(-500 3125);
DISPLAY 1.021277 (-500 3125);
DISPLAY INVISIBLE (-500 3125);
FORCEADD UNIVERSAL_GND..1
(-50 2700);
FORCEPROP 3 LASTPIN (-50 2750) SIG_NAME GND\g
J 0
(-40 2760);
DISPLAY 0.659574 (-40 2760);
PAINT MONO (-40 2760);
DISPLAY INVISIBLE (-40 2760);
FORCEPROP 2 LAST CDS_LIB logical_power
J 0
(-50 2700);
DISPLAY INVISIBLE (-50 2700);
FORCEPROP 1 LAST HDL_POWER GND
J 1
(-25 2625);
DISPLAY 0.872340 (-25 2625);
PAINT GREEN (-25 2625);
DISPLAY INVISIBLE (-25 2625);
FORCEPROP 1 LAST PATH I44
J 0
(25 2700);
DISPLAY 0.872340 (25 2700);
PAINT AQUA (25 2700);
DISPLAY INVISIBLE (25 2700);
FORCEADD OFFPAGE..2
(1675 3225);
FORCEPROP 2 LAST $XR0 14 
J 0
(1864 3225);
DISPLAY 0.638298 (1864 3225);
PAINT MONO (1864 3225);
FORCEPROP 2 LAST CDS_LIB standard
J 0
(1675 3225);
DISPLAY INVISIBLE (1675 3225);
FORCEPROP 1 LAST OFFPAGE TRUE
J 0
(2000 3100);
DISPLAY 0.872340 (2000 3100);
PAINT GREEN (2000 3100);
DISPLAY INVISIBLE (2000 3100);
FORCEPROP 1 LAST COMMENT_BODY TRUE
J 0
(1630 3130);
DISPLAY 0.872340 (1630 3130);
PAINT GREEN (1630 3130);
DISPLAY INVISIBLE (1630 3130);
FORCEPROP 2 LAST PATH I49
J 0
(1875 3275);
DISPLAY 1.021277 (1875 3275);
DISPLAY INVISIBLE (1875 3275);
FORCEADD OFFPAGE..2
(1675 3350);
FORCEPROP 2 LAST $XR0 13 
J 0
(1864 3350);
DISPLAY 0.638298 (1864 3350);
PAINT MONO (1864 3350);
FORCEPROP 2 LAST CDS_LIB standard
J 0
(1675 3350);
DISPLAY INVISIBLE (1675 3350);
FORCEPROP 1 LAST OFFPAGE TRUE
J 0
(2000 3225);
DISPLAY 0.872340 (2000 3225);
PAINT GREEN (2000 3225);
DISPLAY INVISIBLE (2000 3225);
FORCEPROP 1 LAST COMMENT_BODY TRUE
J 0
(1630 3255);
DISPLAY 0.872340 (1630 3255);
PAINT GREEN (1630 3255);
DISPLAY INVISIBLE (1630 3255);
FORCEPROP 2 LAST PATH I50
J 0
(1875 3400);
DISPLAY 1.021277 (1875 3400);
DISPLAY INVISIBLE (1875 3400);
FORCEADD Q_RES..1
(-2075 2700);
FORCEPROP 1 LAST PART_NUMBER CS12402FB01
J 0
(-2175 2750);
DISPLAY 0.510638 (-2175 2750);
DISPLAY INVISIBLE (-2175 2750);
FORCEPROP 1 LAST TOLERANCE 1%
J 0
(-1850 2700);
DISPLAY 0.638298 (-1850 2700);
FORCEPROP 1 LAST MATERIAL CHIP
J 0
(-1750 2700);
DISPLAY 0.638298 (-1750 2700);
FORCEPROP 1 LAST VALUE 240
J 2
(-1875 2700);
DISPLAY 0.638298 (-1875 2700);
FORCEPROP 1 LAST $LOCATION R282
J 0
(-2300 2700);
DISPLAY 0.787234 (-2300 2700);
FORCEPROP 1 LASTPIN (-2175 2700) $PN 1
J 0
(-2163 2712);
DISPLAY 0.787234 (-2163 2712);
FORCEPROP 1 LASTPIN (-1975 2700) $PN 2
J 0
(-2013 2712);
DISPLAY 0.787234 (-2013 2712);
FORCEPROP 2 LAST CDS_LIB pure_quanta
J 0
(-2075 2700);
PAINT MONO (-2075 2700);
DISPLAY INVISIBLE (-2075 2700);
FORCEPROP 1 LAST PACK_TYPE 0402LF
J 0
(-2175 2775);
DISPLAY 0.510638 (-2175 2775);
DISPLAY INVISIBLE (-2175 2775);
FORCEPROP 1 LAST WATTAGE 1/16W
J 2
(-1875 2775);
DISPLAY 0.510638 (-1875 2775);
DISPLAY INVISIBLE (-1875 2775);
FORCEPROP 1 LAST PATH I53
J 0
(-2125 2850);
DISPLAY 0.978723 (-2125 2850);
PAINT WHITE (-2125 2850);
DISPLAY INVISIBLE (-2125 2850);
FORCEPROP 2 LAST CDS_LOCATION R282
J 0
(-2125 2900);
DISPLAY 1.021277 (-2125 2900);
DISPLAY INVISIBLE (-2125 2900);
FORCEPROP 2 LAST $SEC 1
J 0
(-2125 2900);
DISPLAY 0.680851 (-2125 2900);
PAINT MONO (-2125 2900);
DISPLAY INVISIBLE (-2125 2900);
FORCEPROP 2 LAST CDS_SEC 1
J 0
(-2125 2900);
DISPLAY 1.021277 (-2125 2900);
DISPLAY INVISIBLE (-2125 2900);
FORCEADD Q_RES..1
(-2075 3075);
FORCEPROP 1 LAST PART_NUMBER CS12402FB01
J 0
(-2175 3125);
DISPLAY 0.510638 (-2175 3125);
DISPLAY INVISIBLE (-2175 3125);
FORCEPROP 1 LAST MATERIAL EMPTY
J 0
(-1750 3075);
DISPLAY 0.638298 (-1750 3075);
PAINT RED (-1750 3075);
FORCEPROP 1 LAST VALUE 240
J 2
(-1875 3075);
DISPLAY 0.638298 (-1875 3075);
FORCEPROP 1 LAST TOLERANCE 1%
J 0
(-1850 3075);
DISPLAY 0.638298 (-1850 3075);
FORCEPROP 1 LAST $LOCATION R279
J 0
(-2300 3075);
DISPLAY 0.787234 (-2300 3075);
FORCEPROP 1 LASTPIN (-2175 3075) $PN 1
J 0
(-2163 3087);
DISPLAY 0.787234 (-2163 3087);
FORCEPROP 1 LASTPIN (-1975 3075) $PN 2
J 0
(-2013 3087);
DISPLAY 0.787234 (-2013 3087);
FORCEPROP 2 LAST CDS_LIB pure_quanta
J 0
(-2075 3075);
PAINT MONO (-2075 3075);
DISPLAY INVISIBLE (-2075 3075);
FORCEPROP 1 LAST PACK_TYPE 0402LF
J 0
(-2175 3150);
DISPLAY 0.510638 (-2175 3150);
DISPLAY INVISIBLE (-2175 3150);
FORCEPROP 1 LAST WATTAGE 1/16W
J 2
(-1900 3150);
DISPLAY 0.510638 (-1900 3150);
DISPLAY INVISIBLE (-1900 3150);
FORCEPROP 1 LAST PATH I54
J 0
(-2125 3225);
DISPLAY 0.978723 (-2125 3225);
PAINT WHITE (-2125 3225);
DISPLAY INVISIBLE (-2125 3225);
FORCEPROP 2 LAST CDS_LOCATION R279
J 0
(-2125 3275);
DISPLAY 1.021277 (-2125 3275);
DISPLAY INVISIBLE (-2125 3275);
FORCEPROP 2 LAST $SEC 1
J 0
(-2125 3275);
DISPLAY 0.680851 (-2125 3275);
PAINT MONO (-2125 3275);
DISPLAY INVISIBLE (-2125 3275);
FORCEPROP 2 LAST CDS_SEC 1
J 0
(-2125 3275);
DISPLAY 1.021277 (-2125 3275);
DISPLAY INVISIBLE (-2125 3275);
FORCEADD OFFPAGE..2
(-700 2950);
FORCEPROP 2 LAST $XR0 13 
J 0
(-511 2950);
DISPLAY 0.638298 (-511 2950);
PAINT MONO (-511 2950);
FORCEPROP 2 LAST CDS_LIB standard
J 0
(-700 2950);
DISPLAY INVISIBLE (-700 2950);
FORCEPROP 1 LAST OFFPAGE TRUE
J 0
(-375 2825);
DISPLAY 0.872340 (-375 2825);
PAINT GREEN (-375 2825);
DISPLAY INVISIBLE (-375 2825);
FORCEPROP 1 LAST COMMENT_BODY TRUE
J 0
(-745 2855);
DISPLAY 0.872340 (-745 2855);
PAINT GREEN (-745 2855);
DISPLAY INVISIBLE (-745 2855);
FORCEPROP 2 LAST PATH I56
J 0
(-500 3000);
DISPLAY 1.021277 (-500 3000);
DISPLAY INVISIBLE (-500 3000);
FORCEADD Q_RES..1
(-2075 2950);
FORCEPROP 1 LAST PART_NUMBER CS12402FB01
J 0
(-2175 3000);
DISPLAY 0.510638 (-2175 3000);
DISPLAY INVISIBLE (-2175 3000);
FORCEPROP 1 LAST TOLERANCE 1%
J 0
(-1850 2950);
DISPLAY 0.638298 (-1850 2950);
FORCEPROP 1 LAST MATERIAL EMPTY
J 0
(-1750 2950);
DISPLAY 0.638298 (-1750 2950);
PAINT RED (-1750 2950);
FORCEPROP 1 LAST VALUE 240
J 2
(-1875 2950);
DISPLAY 0.638298 (-1875 2950);
FORCEPROP 1 LAST $LOCATION R280
J 0
(-2300 2950);
DISPLAY 0.787234 (-2300 2950);
FORCEPROP 1 LASTPIN (-2175 2950) $PN 1
J 0
(-2163 2962);
DISPLAY 0.787234 (-2163 2962);
FORCEPROP 1 LASTPIN (-1975 2950) $PN 2
J 0
(-2013 2962);
DISPLAY 0.787234 (-2013 2962);
FORCEPROP 2 LAST CDS_LIB pure_quanta
J 0
(-2075 2950);
PAINT MONO (-2075 2950);
DISPLAY INVISIBLE (-2075 2950);
FORCEPROP 1 LAST WATTAGE 1/16W
J 2
(-1900 3025);
DISPLAY 0.510638 (-1900 3025);
DISPLAY INVISIBLE (-1900 3025);
FORCEPROP 1 LAST PACK_TYPE 0402LF
J 0
(-2175 3025);
DISPLAY 0.510638 (-2175 3025);
DISPLAY INVISIBLE (-2175 3025);
FORCEPROP 1 LAST PATH I57
J 0
(-2125 3100);
DISPLAY 0.978723 (-2125 3100);
PAINT WHITE (-2125 3100);
DISPLAY INVISIBLE (-2125 3100);
FORCEPROP 2 LAST CDS_LOCATION R280
J 0
(-2125 3150);
DISPLAY 1.021277 (-2125 3150);
DISPLAY INVISIBLE (-2125 3150);
FORCEPROP 2 LAST $SEC 1
J 0
(-2125 3150);
DISPLAY 0.680851 (-2125 3150);
PAINT MONO (-2125 3150);
DISPLAY INVISIBLE (-2125 3150);
FORCEPROP 2 LAST CDS_SEC 1
J 0
(-2125 3150);
DISPLAY 1.021277 (-2125 3150);
DISPLAY INVISIBLE (-2125 3150);
FORCEADD Q_RES..1
(-2075 2825);
FORCEPROP 1 LAST PART_NUMBER CS12402FB01
J 0
(-2175 2875);
DISPLAY 0.510638 (-2175 2875);
DISPLAY INVISIBLE (-2175 2875);
FORCEPROP 1 LAST MATERIAL EMPTY
J 0
(-1750 2825);
DISPLAY 0.638298 (-1750 2825);
PAINT RED (-1750 2825);
FORCEPROP 1 LAST TOLERANCE 1%
J 0
(-1850 2825);
DISPLAY 0.638298 (-1850 2825);
FORCEPROP 1 LAST VALUE 240
J 2
(-1875 2825);
DISPLAY 0.638298 (-1875 2825);
FORCEPROP 1 LAST $LOCATION R281
J 0
(-2300 2825);
DISPLAY 0.787234 (-2300 2825);
FORCEPROP 1 LASTPIN (-2175 2825) $PN 1
J 0
(-2163 2837);
DISPLAY 0.787234 (-2163 2837);
FORCEPROP 1 LASTPIN (-1975 2825) $PN 2
J 0
(-2013 2837);
DISPLAY 0.787234 (-2013 2837);
FORCEPROP 2 LAST CDS_LIB pure_quanta
J 0
(-2075 2825);
PAINT MONO (-2075 2825);
DISPLAY INVISIBLE (-2075 2825);
FORCEPROP 1 LAST PACK_TYPE 0402LF
J 0
(-2175 2900);
DISPLAY 0.510638 (-2175 2900);
DISPLAY INVISIBLE (-2175 2900);
FORCEPROP 1 LAST WATTAGE 1/16W
J 2
(-1900 2900);
DISPLAY 0.510638 (-1900 2900);
DISPLAY INVISIBLE (-1900 2900);
FORCEPROP 1 LAST PATH I58
J 0
(-2125 2975);
DISPLAY 0.978723 (-2125 2975);
PAINT WHITE (-2125 2975);
DISPLAY INVISIBLE (-2125 2975);
FORCEPROP 2 LAST CDS_LOCATION R281
J 0
(-2125 3025);
DISPLAY 1.021277 (-2125 3025);
DISPLAY INVISIBLE (-2125 3025);
FORCEPROP 2 LAST $SEC 1
J 0
(-2125 3025);
DISPLAY 0.680851 (-2125 3025);
PAINT MONO (-2125 3025);
DISPLAY INVISIBLE (-2125 3025);
FORCEPROP 2 LAST CDS_SEC 1
J 0
(-2125 3025);
DISPLAY 1.021277 (-2125 3025);
DISPLAY INVISIBLE (-2125 3025);
FORCEADD OFFPAGE..2
(-700 2825);
FORCEPROP 2 LAST $XR0 13 
J 0
(-511 2825);
DISPLAY 0.638298 (-511 2825);
PAINT MONO (-511 2825);
FORCEPROP 2 LAST CDS_LIB standard
J 0
(-700 2825);
DISPLAY INVISIBLE (-700 2825);
FORCEPROP 1 LAST OFFPAGE TRUE
J 0
(-375 2700);
DISPLAY 0.872340 (-375 2700);
PAINT GREEN (-375 2700);
DISPLAY INVISIBLE (-375 2700);
FORCEPROP 1 LAST COMMENT_BODY TRUE
J 0
(-745 2730);
DISPLAY 0.872340 (-745 2730);
PAINT GREEN (-745 2730);
DISPLAY INVISIBLE (-745 2730);
FORCEPROP 2 LAST PATH I59
J 0
(-500 2875);
DISPLAY 1.021277 (-500 2875);
DISPLAY INVISIBLE (-500 2875);
FORCEADD OFFPAGE..2
(-700 3200);
FORCEPROP 2 LAST $XR0 13 
J 0
(-511 3200);
DISPLAY 0.638298 (-511 3200);
PAINT MONO (-511 3200);
FORCEPROP 2 LAST CDS_LIB standard
J 0
(-700 3200);
DISPLAY INVISIBLE (-700 3200);
FORCEPROP 1 LAST OFFPAGE TRUE
J 0
(-375 3075);
DISPLAY 0.872340 (-375 3075);
PAINT GREEN (-375 3075);
DISPLAY INVISIBLE (-375 3075);
FORCEPROP 1 LAST COMMENT_BODY TRUE
J 0
(-745 3105);
DISPLAY 0.872340 (-745 3105);
PAINT GREEN (-745 3105);
DISPLAY INVISIBLE (-745 3105);
FORCEPROP 2 LAST PATH I60
J 0
(-500 3250);
DISPLAY 1.021277 (-500 3250);
DISPLAY INVISIBLE (-500 3250);
FORCEADD Q_RES..1
(-2075 3200);
FORCEPROP 1 LAST PART_NUMBER CS12402FB01
J 0
(-2175 3250);
DISPLAY 0.510638 (-2175 3250);
DISPLAY INVISIBLE (-2175 3250);
FORCEPROP 1 LAST MATERIAL EMPTY
J 0
(-1750 3200);
DISPLAY 0.638298 (-1750 3200);
PAINT RED (-1750 3200);
FORCEPROP 1 LAST VALUE 240
J 2
(-1875 3200);
DISPLAY 0.638298 (-1875 3200);
FORCEPROP 1 LAST TOLERANCE 1%
J 0
(-1850 3200);
DISPLAY 0.638298 (-1850 3200);
FORCEPROP 1 LAST $LOCATION R278
J 0
(-2300 3200);
DISPLAY 0.787234 (-2300 3200);
FORCEPROP 1 LASTPIN (-2175 3200) $PN 1
J 0
(-2163 3212);
DISPLAY 0.787234 (-2163 3212);
FORCEPROP 1 LASTPIN (-1975 3200) $PN 2
J 0
(-2013 3212);
DISPLAY 0.787234 (-2013 3212);
FORCEPROP 1 LAST WATTAGE 1/16W
J 2
(-1875 3275);
DISPLAY 0.510638 (-1875 3275);
DISPLAY INVISIBLE (-1875 3275);
FORCEPROP 1 LAST PACK_TYPE 0402LF
J 0
(-2175 3275);
DISPLAY 0.510638 (-2175 3275);
DISPLAY INVISIBLE (-2175 3275);
FORCEPROP 2 LAST CDS_LIB pure_quanta
J 0
(-2075 3200);
PAINT MONO (-2075 3200);
DISPLAY INVISIBLE (-2075 3200);
FORCEPROP 1 LAST PATH I61
J 0
(-2125 3350);
DISPLAY 0.978723 (-2125 3350);
PAINT WHITE (-2125 3350);
DISPLAY INVISIBLE (-2125 3350);
FORCEPROP 2 LAST CDS_LOCATION R278
J 0
(-2125 3400);
DISPLAY 1.021277 (-2125 3400);
DISPLAY INVISIBLE (-2125 3400);
FORCEPROP 2 LAST $SEC 1
J 0
(-2125 3400);
DISPLAY 0.680851 (-2125 3400);
PAINT MONO (-2125 3400);
DISPLAY INVISIBLE (-2125 3400);
FORCEPROP 2 LAST CDS_SEC 1
J 0
(-2125 3400);
DISPLAY 1.021277 (-2125 3400);
DISPLAY INVISIBLE (-2125 3400);
FORCEADD Q_RES..1
(-2075 3325);
FORCEPROP 1 LAST PART_NUMBER CS12402FB01
J 0
(-2175 3375);
DISPLAY 0.510638 (-2175 3375);
DISPLAY INVISIBLE (-2175 3375);
FORCEPROP 1 LAST MATERIAL CHIP
J 0
(-1750 3325);
DISPLAY 0.638298 (-1750 3325);
FORCEPROP 1 LAST TOLERANCE 1%
J 0
(-1850 3325);
DISPLAY 0.638298 (-1850 3325);
FORCEPROP 1 LAST VALUE 240
J 2
(-1875 3325);
DISPLAY 0.638298 (-1875 3325);
FORCEPROP 1 LAST $LOCATION R277
J 0
(-2300 3325);
DISPLAY 0.787234 (-2300 3325);
FORCEPROP 1 LASTPIN (-2175 3325) $PN 1
J 0
(-2163 3337);
DISPLAY 0.787234 (-2163 3337);
FORCEPROP 1 LASTPIN (-1975 3325) $PN 2
J 0
(-2013 3337);
DISPLAY 0.787234 (-2013 3337);
FORCEPROP 2 LAST CDS_LIB pure_quanta
J 0
(-2075 3325);
PAINT MONO (-2075 3325);
DISPLAY INVISIBLE (-2075 3325);
FORCEPROP 1 LAST PACK_TYPE 0402LF
J 0
(-2175 3400);
DISPLAY 0.510638 (-2175 3400);
DISPLAY INVISIBLE (-2175 3400);
FORCEPROP 1 LAST WATTAGE 1/16W
J 2
(-1875 3400);
DISPLAY 0.510638 (-1875 3400);
DISPLAY INVISIBLE (-1875 3400);
FORCEPROP 1 LAST PATH I62
J 0
(-2125 3475);
DISPLAY 0.978723 (-2125 3475);
PAINT WHITE (-2125 3475);
DISPLAY INVISIBLE (-2125 3475);
FORCEPROP 2 LAST CDS_LOCATION R277
J 0
(-2125 3525);
DISPLAY 1.021277 (-2125 3525);
DISPLAY INVISIBLE (-2125 3525);
FORCEPROP 2 LAST $SEC 1
J 0
(-2125 3525);
DISPLAY 0.680851 (-2125 3525);
PAINT MONO (-2125 3525);
DISPLAY INVISIBLE (-2125 3525);
FORCEPROP 2 LAST CDS_SEC 1
J 0
(-2125 3525);
DISPLAY 1.021277 (-2125 3525);
DISPLAY INVISIBLE (-2125 3525);
FORCEADD OFFPAGE..2
(-700 3325);
FORCEPROP 2 LAST $XR0 13 
J 0
(-511 3325);
DISPLAY 0.638298 (-511 3325);
PAINT MONO (-511 3325);
FORCEPROP 2 LAST CDS_LIB standard
J 0
(-700 3325);
DISPLAY INVISIBLE (-700 3325);
FORCEPROP 1 LAST OFFPAGE TRUE
J 0
(-375 3200);
DISPLAY 0.872340 (-375 3200);
PAINT GREEN (-375 3200);
DISPLAY INVISIBLE (-375 3200);
FORCEPROP 1 LAST COMMENT_BODY TRUE
J 0
(-745 3230);
DISPLAY 0.872340 (-745 3230);
PAINT GREEN (-745 3230);
DISPLAY INVISIBLE (-745 3230);
FORCEPROP 2 LAST PATH I63
J 0
(-500 3375);
DISPLAY 1.021277 (-500 3375);
DISPLAY INVISIBLE (-500 3375);
FORCEADD OFFPAGE..2
(-700 3450);
FORCEPROP 2 LAST $XR0 13 
J 0
(-511 3450);
DISPLAY 0.638298 (-511 3450);
PAINT MONO (-511 3450);
FORCEPROP 2 LAST CDS_LIB standard
J 0
(-700 3450);
DISPLAY INVISIBLE (-700 3450);
FORCEPROP 1 LAST OFFPAGE TRUE
J 0
(-375 3325);
DISPLAY 0.872340 (-375 3325);
PAINT GREEN (-375 3325);
DISPLAY INVISIBLE (-375 3325);
FORCEPROP 1 LAST COMMENT_BODY TRUE
J 0
(-745 3355);
DISPLAY 0.872340 (-745 3355);
PAINT GREEN (-745 3355);
DISPLAY INVISIBLE (-745 3355);
FORCEPROP 2 LAST PATH I65
J 0
(-500 3500);
DISPLAY 1.021277 (-500 3500);
DISPLAY INVISIBLE (-500 3500);
FORCEADD Q_RES..1
(-2075 3450);
FORCEPROP 1 LAST PART_NUMBER CS12402FB01
J 0
(-2175 3500);
DISPLAY 0.510638 (-2175 3500);
DISPLAY INVISIBLE (-2175 3500);
FORCEPROP 1 LAST TOLERANCE 1%
J 0
(-1850 3450);
DISPLAY 0.638298 (-1850 3450);
FORCEPROP 1 LAST VALUE 240
J 2
(-1875 3450);
DISPLAY 0.638298 (-1875 3450);
FORCEPROP 1 LAST MATERIAL EMPTY
J 0
(-1750 3450);
DISPLAY 0.638298 (-1750 3450);
PAINT RED (-1750 3450);
FORCEPROP 1 LAST $LOCATION R276
J 0
(-2300 3450);
DISPLAY 0.787234 (-2300 3450);
FORCEPROP 1 LASTPIN (-2175 3450) $PN 1
J 0
(-2163 3462);
DISPLAY 0.787234 (-2163 3462);
FORCEPROP 1 LASTPIN (-1975 3450) $PN 2
J 0
(-2013 3462);
DISPLAY 0.787234 (-2013 3462);
FORCEPROP 2 LAST CDS_LIB pure_quanta
J 0
(-2075 3450);
PAINT MONO (-2075 3450);
DISPLAY INVISIBLE (-2075 3450);
FORCEPROP 1 LAST PACK_TYPE 0402LF
J 0
(-2175 3525);
DISPLAY 0.510638 (-2175 3525);
DISPLAY INVISIBLE (-2175 3525);
FORCEPROP 1 LAST WATTAGE 1/16W
J 2
(-1900 3525);
DISPLAY 0.510638 (-1900 3525);
DISPLAY INVISIBLE (-1900 3525);
FORCEPROP 1 LAST PATH I66
J 0
(-2125 3600);
DISPLAY 0.978723 (-2125 3600);
PAINT WHITE (-2125 3600);
DISPLAY INVISIBLE (-2125 3600);
FORCEPROP 2 LAST CDS_LOCATION R276
J 0
(-2125 3650);
DISPLAY 1.021277 (-2125 3650);
DISPLAY INVISIBLE (-2125 3650);
FORCEPROP 2 LAST $SEC 1
J 0
(-2125 3650);
DISPLAY 0.680851 (-2125 3650);
PAINT MONO (-2125 3650);
DISPLAY INVISIBLE (-2125 3650);
FORCEPROP 2 LAST CDS_SEC 1
J 0
(-2125 3650);
DISPLAY 1.021277 (-2125 3650);
DISPLAY INVISIBLE (-2125 3650);
FORCEADD OFFPAGE..2
(-700 3575);
FORCEPROP 2 LAST $XR0 13 
J 0
(-511 3575);
DISPLAY 0.638298 (-511 3575);
PAINT MONO (-511 3575);
FORCEPROP 2 LAST CDS_LIB standard
J 0
(-700 3575);
DISPLAY INVISIBLE (-700 3575);
FORCEPROP 1 LAST OFFPAGE TRUE
J 0
(-375 3450);
DISPLAY 0.872340 (-375 3450);
PAINT GREEN (-375 3450);
DISPLAY INVISIBLE (-375 3450);
FORCEPROP 1 LAST COMMENT_BODY TRUE
J 0
(-745 3480);
DISPLAY 0.872340 (-745 3480);
PAINT GREEN (-745 3480);
DISPLAY INVISIBLE (-745 3480);
FORCEPROP 2 LAST PATH I67
J 0
(-500 3625);
DISPLAY 1.021277 (-500 3625);
DISPLAY INVISIBLE (-500 3625);
FORCEADD Q_RES..1
(-2075 3575);
FORCEPROP 1 LAST PART_NUMBER CS12402FB01
J 0
(-2175 3625);
DISPLAY 0.510638 (-2175 3625);
DISPLAY INVISIBLE (-2175 3625);
FORCEPROP 1 LAST WATTAGE 1/16W
J 2
(-1900 3650);
DISPLAY 0.510638 (-1900 3650);
FORCEPROP 1 LAST TOLERANCE 1%
J 0
(-1850 3575);
DISPLAY 0.638298 (-1850 3575);
FORCEPROP 1 LAST MATERIAL CHIP
J 0
(-1750 3575);
DISPLAY 0.638298 (-1750 3575);
FORCEPROP 1 LAST VALUE 240
J 2
(-1875 3575);
DISPLAY 0.638298 (-1875 3575);
FORCEPROP 1 LAST PACK_TYPE 0402LF
J 0
(-2175 3650);
DISPLAY 0.510638 (-2175 3650);
FORCEPROP 1 LAST $LOCATION R275
J 0
(-2300 3575);
DISPLAY 0.787234 (-2300 3575);
FORCEPROP 1 LASTPIN (-2175 3575) $PN 1
J 0
(-2163 3587);
DISPLAY 0.787234 (-2163 3587);
FORCEPROP 1 LASTPIN (-1975 3575) $PN 2
J 0
(-2013 3587);
DISPLAY 0.787234 (-2013 3587);
FORCEPROP 2 LAST CDS_LIB pure_quanta
J 0
(-2075 3575);
PAINT MONO (-2075 3575);
DISPLAY INVISIBLE (-2075 3575);
FORCEPROP 1 LAST PATH I68
J 0
(-2125 3725);
DISPLAY 0.978723 (-2125 3725);
PAINT WHITE (-2125 3725);
DISPLAY INVISIBLE (-2125 3725);
FORCEPROP 2 LAST CDS_LOCATION R275
J 0
(-2125 3775);
DISPLAY 1.021277 (-2125 3775);
DISPLAY INVISIBLE (-2125 3775);
FORCEPROP 2 LAST $SEC 1
J 0
(-2125 3775);
DISPLAY 0.680851 (-2125 3775);
PAINT MONO (-2125 3775);
DISPLAY INVISIBLE (-2125 3775);
FORCEPROP 2 LAST CDS_SEC 1
J 0
(-2125 3775);
DISPLAY 1.021277 (-2125 3775);
DISPLAY INVISIBLE (-2125 3775);
FORCEADD Q_RES..1
(275 3350);
FORCEPROP 1 LAST PART_NUMBER CS12402FB01
J 0
(175 3400);
DISPLAY 0.510638 (175 3400);
DISPLAY INVISIBLE (175 3400);
FORCEPROP 1 LAST MATERIAL EMPTY
J 0
(600 3350);
DISPLAY 0.638298 (600 3350);
PAINT RED (600 3350);
FORCEPROP 1 LAST TOLERANCE 1%
J 0
(500 3350);
DISPLAY 0.638298 (500 3350);
FORCEPROP 1 LAST VALUE 240
J 2
(475 3350);
DISPLAY 0.638298 (475 3350);
FORCEPROP 1 LAST $LOCATION R294
J 0
(50 3350);
DISPLAY 0.787234 (50 3350);
FORCEPROP 1 LASTPIN (175 3350) $PN 1
J 0
(187 3362);
DISPLAY 0.787234 (187 3362);
FORCEPROP 1 LASTPIN (375 3350) $PN 2
J 0
(337 3362);
DISPLAY 0.787234 (337 3362);
FORCEPROP 2 LAST CDS_LIB pure_quanta
J 0
(275 3350);
PAINT MONO (275 3350);
DISPLAY INVISIBLE (275 3350);
FORCEPROP 1 LAST PACK_TYPE 0402LF
J 0
(175 3425);
DISPLAY 0.510638 (175 3425);
DISPLAY INVISIBLE (175 3425);
FORCEPROP 1 LAST WATTAGE 1/16W
J 2
(450 3425);
DISPLAY 0.510638 (450 3425);
DISPLAY INVISIBLE (450 3425);
FORCEPROP 1 LAST PATH I71
J 0
(225 3500);
DISPLAY 0.978723 (225 3500);
PAINT WHITE (225 3500);
DISPLAY INVISIBLE (225 3500);
FORCEPROP 2 LAST CDS_LOCATION R294
J 0
(225 3550);
DISPLAY 1.021277 (225 3550);
DISPLAY INVISIBLE (225 3550);
FORCEPROP 2 LAST $SEC 1
J 0
(225 3550);
DISPLAY 0.680851 (225 3550);
PAINT MONO (225 3550);
DISPLAY INVISIBLE (225 3550);
FORCEPROP 2 LAST CDS_SEC 1
J 0
(225 3550);
DISPLAY 1.021277 (225 3550);
DISPLAY INVISIBLE (225 3550);
FORCEADD Q_RES..1
(275 3225);
FORCEPROP 1 LAST PART_NUMBER CS12402FB01
J 0
(175 3275);
DISPLAY 0.510638 (175 3275);
DISPLAY INVISIBLE (175 3275);
FORCEPROP 1 LAST VALUE 240
J 2
(475 3225);
DISPLAY 0.638298 (475 3225);
FORCEPROP 1 LAST TOLERANCE 1%
J 0
(500 3225);
DISPLAY 0.638298 (500 3225);
FORCEPROP 1 LAST MATERIAL EMPTY
J 0
(600 3225);
DISPLAY 0.638298 (600 3225);
PAINT RED (600 3225);
FORCEPROP 1 LAST $LOCATION R295
J 0
(50 3225);
DISPLAY 0.787234 (50 3225);
FORCEPROP 1 LASTPIN (175 3225) $PN 1
J 0
(187 3237);
DISPLAY 0.787234 (187 3237);
FORCEPROP 1 LASTPIN (375 3225) $PN 2
J 0
(337 3237);
DISPLAY 0.787234 (337 3237);
FORCEPROP 2 LAST CDS_LIB pure_quanta
J 0
(275 3225);
PAINT MONO (275 3225);
DISPLAY INVISIBLE (275 3225);
FORCEPROP 1 LAST WATTAGE 1/16W
J 2
(450 3300);
DISPLAY 0.510638 (450 3300);
DISPLAY INVISIBLE (450 3300);
FORCEPROP 1 LAST PACK_TYPE 0402LF
J 0
(175 3300);
DISPLAY 0.510638 (175 3300);
DISPLAY INVISIBLE (175 3300);
FORCEPROP 1 LAST PATH I72
J 0
(225 3375);
DISPLAY 0.978723 (225 3375);
PAINT WHITE (225 3375);
DISPLAY INVISIBLE (225 3375);
FORCEPROP 2 LAST CDS_LOCATION R295
J 0
(225 3425);
DISPLAY 1.021277 (225 3425);
DISPLAY INVISIBLE (225 3425);
FORCEPROP 2 LAST $SEC 1
J 0
(225 3425);
DISPLAY 0.680851 (225 3425);
PAINT MONO (225 3425);
DISPLAY INVISIBLE (225 3425);
FORCEPROP 2 LAST CDS_SEC 1
J 0
(225 3425);
DISPLAY 1.021277 (225 3425);
DISPLAY INVISIBLE (225 3425);
FORCEADD Q_RES..1
(225 -1275);
FORCEPROP 1 LAST PART_NUMBER CS31002FB08
J 0
(125 -1225);
DISPLAY 0.510638 (125 -1225);
DISPLAY INVISIBLE (125 -1225);
FORCEPROP 1 LAST MATERIAL CHIP
J 0
(550 -1275);
DISPLAY 0.638298 (550 -1275);
FORCEPROP 1 LAST TOLERANCE 1%
J 0
(450 -1275);
DISPLAY 0.638298 (450 -1275);
FORCEPROP 1 LAST VALUE 10K
J 2
(425 -1275);
DISPLAY 0.638298 (425 -1275);
FORCEPROP 1 LAST $LOCATION R274
J 0
(0 -1275);
DISPLAY 0.787234 (0 -1275);
FORCEPROP 1 LASTPIN (125 -1275) $PN 1
J 0
(137 -1263);
DISPLAY 0.787234 (137 -1263);
FORCEPROP 1 LASTPIN (325 -1275) $PN 2
J 0
(287 -1263);
DISPLAY 0.787234 (287 -1263);
FORCEPROP 2 LAST CDS_LIB pure_quanta
J 0
(225 -1275);
PAINT MONO (225 -1275);
DISPLAY INVISIBLE (225 -1275);
FORCEPROP 1 LAST PACK_TYPE 0402LF
J 0
(125 -1200);
DISPLAY 0.510638 (125 -1200);
DISPLAY INVISIBLE (125 -1200);
FORCEPROP 1 LAST WATTAGE 1/16W
J 2
(425 -1200);
DISPLAY 0.510638 (425 -1200);
DISPLAY INVISIBLE (425 -1200);
FORCEPROP 1 LAST PATH I88
J 0
(175 -1125);
DISPLAY 0.978723 (175 -1125);
PAINT WHITE (175 -1125);
DISPLAY INVISIBLE (175 -1125);
FORCEPROP 2 LAST CDS_LOCATION R274
J 0
(175 -1075);
DISPLAY 1.021277 (175 -1075);
DISPLAY INVISIBLE (175 -1075);
FORCEPROP 2 LAST $SEC 1
J 0
(175 -1075);
DISPLAY 0.680851 (175 -1075);
PAINT MONO (175 -1075);
DISPLAY INVISIBLE (175 -1075);
FORCEPROP 2 LAST CDS_SEC 1
J 0
(175 -1075);
DISPLAY 1.021277 (175 -1075);
DISPLAY INVISIBLE (175 -1075);
FORCEADD Q_RES..1
(225 -1150);
FORCEPROP 1 LAST PART_NUMBER CS31002FB08
J 0
(125 -1100);
DISPLAY 0.510638 (125 -1100);
DISPLAY INVISIBLE (125 -1100);
FORCEPROP 1 LAST MATERIAL CHIP
J 0
(550 -1150);
DISPLAY 0.638298 (550 -1150);
FORCEPROP 1 LAST TOLERANCE 1%
J 0
(450 -1150);
DISPLAY 0.638298 (450 -1150);
FORCEPROP 1 LAST VALUE 10K
J 2
(425 -1150);
DISPLAY 0.638298 (425 -1150);
FORCEPROP 1 LAST $LOCATION R273
J 0
(0 -1150);
DISPLAY 0.787234 (0 -1150);
FORCEPROP 1 LASTPIN (125 -1150) $PN 1
J 0
(137 -1138);
DISPLAY 0.787234 (137 -1138);
FORCEPROP 1 LASTPIN (325 -1150) $PN 2
J 0
(287 -1138);
DISPLAY 0.787234 (287 -1138);
FORCEPROP 2 LAST CDS_LIB pure_quanta
J 0
(225 -1150);
PAINT MONO (225 -1150);
DISPLAY INVISIBLE (225 -1150);
FORCEPROP 1 LAST WATTAGE 1/16W
J 2
(425 -1075);
DISPLAY 0.510638 (425 -1075);
DISPLAY INVISIBLE (425 -1075);
FORCEPROP 1 LAST PACK_TYPE 0402LF
J 0
(125 -1075);
DISPLAY 0.510638 (125 -1075);
DISPLAY INVISIBLE (125 -1075);
FORCEPROP 1 LAST PATH I89
J 0
(175 -1000);
DISPLAY 0.978723 (175 -1000);
PAINT WHITE (175 -1000);
DISPLAY INVISIBLE (175 -1000);
FORCEPROP 2 LAST CDS_LOCATION R273
J 0
(175 -950);
DISPLAY 1.021277 (175 -950);
DISPLAY INVISIBLE (175 -950);
FORCEPROP 2 LAST $SEC 1
J 0
(175 -950);
DISPLAY 0.680851 (175 -950);
PAINT MONO (175 -950);
DISPLAY INVISIBLE (175 -950);
FORCEPROP 2 LAST CDS_SEC 1
J 0
(175 -950);
DISPLAY 1.021277 (175 -950);
DISPLAY INVISIBLE (175 -950);
FORCEADD Q_RES..1
(225 -1025);
FORCEPROP 1 LAST PART_NUMBER CS31002FB08
J 0
(125 -975);
DISPLAY 0.510638 (125 -975);
DISPLAY INVISIBLE (125 -975);
FORCEPROP 1 LAST VALUE 10K
J 2
(425 -1025);
DISPLAY 0.638298 (425 -1025);
FORCEPROP 1 LAST TOLERANCE 1%
J 0
(450 -1025);
DISPLAY 0.638298 (450 -1025);
FORCEPROP 1 LAST MATERIAL CHIP
J 0
(550 -1025);
DISPLAY 0.638298 (550 -1025);
FORCEPROP 1 LAST $LOCATION R272
J 0
(0 -1025);
DISPLAY 0.787234 (0 -1025);
FORCEPROP 1 LASTPIN (125 -1025) $PN 1
J 0
(137 -1013);
DISPLAY 0.787234 (137 -1013);
FORCEPROP 1 LASTPIN (325 -1025) $PN 2
J 0
(287 -1013);
DISPLAY 0.787234 (287 -1013);
FORCEPROP 2 LAST CDS_LIB pure_quanta
J 0
(225 -1025);
PAINT MONO (225 -1025);
DISPLAY INVISIBLE (225 -1025);
FORCEPROP 1 LAST WATTAGE 1/16W
J 2
(425 -950);
DISPLAY 0.510638 (425 -950);
DISPLAY INVISIBLE (425 -950);
FORCEPROP 1 LAST PACK_TYPE 0402LF
J 0
(125 -950);
DISPLAY 0.510638 (125 -950);
DISPLAY INVISIBLE (125 -950);
FORCEPROP 1 LAST PATH I90
J 0
(175 -875);
DISPLAY 0.978723 (175 -875);
PAINT WHITE (175 -875);
DISPLAY INVISIBLE (175 -875);
FORCEPROP 2 LAST CDS_LOCATION R272
J 0
(175 -825);
DISPLAY 1.021277 (175 -825);
DISPLAY INVISIBLE (175 -825);
FORCEPROP 2 LAST $SEC 1
J 0
(175 -825);
DISPLAY 0.680851 (175 -825);
PAINT MONO (175 -825);
DISPLAY INVISIBLE (175 -825);
FORCEPROP 2 LAST CDS_SEC 1
J 0
(175 -825);
DISPLAY 1.021277 (175 -825);
DISPLAY INVISIBLE (175 -825);
FORCEADD UNIVERSAL_POWER..1
(-75 -625);
FORCEPROP 3 LASTPIN (-75 -675) SIG_NAME P3V3_AUX\g
J 0
(-65 -665);
DISPLAY 0.659574 (-65 -665);
PAINT MONO (-65 -665);
DISPLAY INVISIBLE (-65 -665);
FORCEPROP 1 LAST HDL_POWER P3V3_AUX
J 1
(-75 -575);
DISPLAY 0.872340 (-75 -575);
PAINT GREEN (-75 -575);
FORCEPROP 2 LAST CDS_LIB logical_power
J 0
(-75 -625);
DISPLAY INVISIBLE (-75 -625);
FORCEPROP 1 LAST PATH I91
J 0
(-25 -600);
DISPLAY 0.872340 (-25 -600);
PAINT AQUA (-25 -600);
DISPLAY INVISIBLE (-25 -600);
FORCEADD Q_RES..1
(225 -900);
FORCEPROP 1 LAST PART_NUMBER CS31002FB08
J 0
(125 -850);
DISPLAY 0.510638 (125 -850);
DISPLAY INVISIBLE (125 -850);
FORCEPROP 1 LAST MATERIAL CHIP
J 0
(550 -900);
DISPLAY 0.638298 (550 -900);
FORCEPROP 1 LAST TOLERANCE 1%
J 0
(450 -900);
DISPLAY 0.638298 (450 -900);
FORCEPROP 1 LAST VALUE 10K
J 2
(425 -900);
DISPLAY 0.638298 (425 -900);
FORCEPROP 1 LAST $LOCATION R271
J 0
(0 -900);
DISPLAY 0.787234 (0 -900);
FORCEPROP 1 LASTPIN (125 -900) $PN 1
J 0
(137 -888);
DISPLAY 0.787234 (137 -888);
FORCEPROP 1 LASTPIN (325 -900) $PN 2
J 0
(287 -888);
DISPLAY 0.787234 (287 -888);
FORCEPROP 2 LAST CDS_LIB pure_quanta
J 0
(225 -900);
PAINT MONO (225 -900);
DISPLAY INVISIBLE (225 -900);
FORCEPROP 1 LAST PACK_TYPE 0402LF
J 0
(125 -825);
DISPLAY 0.510638 (125 -825);
DISPLAY INVISIBLE (125 -825);
FORCEPROP 1 LAST WATTAGE 1/16W
J 2
(425 -825);
DISPLAY 0.510638 (425 -825);
DISPLAY INVISIBLE (425 -825);
FORCEPROP 1 LAST PATH I92
J 0
(175 -750);
DISPLAY 0.978723 (175 -750);
PAINT WHITE (175 -750);
DISPLAY INVISIBLE (175 -750);
FORCEPROP 2 LAST CDS_LOCATION R271
J 0
(175 -700);
DISPLAY 1.021277 (175 -700);
DISPLAY INVISIBLE (175 -700);
FORCEPROP 2 LAST $SEC 1
J 0
(175 -700);
DISPLAY 0.680851 (175 -700);
PAINT MONO (175 -700);
DISPLAY INVISIBLE (175 -700);
FORCEPROP 2 LAST CDS_SEC 1
J 0
(175 -700);
DISPLAY 1.021277 (175 -700);
DISPLAY INVISIBLE (175 -700);
FORCEADD Q_RES..1
(225 -775);
FORCEPROP 1 LAST PART_NUMBER CS31002FB08
J 0
(125 -725);
DISPLAY 0.510638 (125 -725);
DISPLAY INVISIBLE (125 -725);
FORCEPROP 1 LAST MATERIAL CHIP
J 0
(550 -775);
DISPLAY 0.638298 (550 -775);
FORCEPROP 1 LAST PACK_TYPE 0402LF
J 0
(125 -700);
DISPLAY 0.510638 (125 -700);
FORCEPROP 1 LAST TOLERANCE 1%
J 0
(450 -775);
DISPLAY 0.638298 (450 -775);
FORCEPROP 1 LAST WATTAGE 1/16W
J 2
(425 -700);
DISPLAY 0.510638 (425 -700);
FORCEPROP 1 LAST VALUE 10K
J 2
(425 -775);
DISPLAY 0.638298 (425 -775);
FORCEPROP 1 LAST $LOCATION R270
J 0
(0 -775);
DISPLAY 0.787234 (0 -775);
FORCEPROP 1 LASTPIN (125 -775) $PN 1
J 0
(137 -763);
DISPLAY 0.787234 (137 -763);
FORCEPROP 1 LASTPIN (325 -775) $PN 2
J 0
(287 -763);
DISPLAY 0.787234 (287 -763);
FORCEPROP 2 LAST CDS_LIB pure_quanta
J 0
(225 -775);
PAINT MONO (225 -775);
DISPLAY INVISIBLE (225 -775);
FORCEPROP 1 LAST PATH I93
J 0
(175 -625);
DISPLAY 0.978723 (175 -625);
PAINT WHITE (175 -625);
DISPLAY INVISIBLE (175 -625);
FORCEPROP 2 LAST CDS_LOCATION R270
J 0
(175 -575);
DISPLAY 1.021277 (175 -575);
DISPLAY INVISIBLE (175 -575);
FORCEPROP 2 LAST $SEC 1
J 0
(175 -575);
DISPLAY 0.680851 (175 -575);
PAINT MONO (175 -575);
DISPLAY INVISIBLE (175 -575);
FORCEPROP 2 LAST CDS_SEC 1
J 0
(175 -575);
DISPLAY 1.021277 (175 -575);
DISPLAY INVISIBLE (175 -575);
FORCEADD Q_RES..1
(-2100 -275);
FORCEPROP 1 LAST PART_NUMBER CS12402FB01
J 0
(-2200 -225);
DISPLAY 0.510638 (-2200 -225);
DISPLAY INVISIBLE (-2200 -225);
FORCEPROP 1 LAST MATERIAL EMPTY
J 0
(-1775 -275);
DISPLAY 0.638298 (-1775 -275);
PAINT RED (-1775 -275);
FORCEPROP 1 LAST VALUE 240
J 2
(-1900 -275);
DISPLAY 0.638298 (-1900 -275);
FORCEPROP 1 LAST TOLERANCE 1%
J 0
(-1875 -275);
DISPLAY 0.638298 (-1875 -275);
FORCEPROP 1 LAST $LOCATION R268
J 0
(-2325 -275);
DISPLAY 0.787234 (-2325 -275);
FORCEPROP 1 LASTPIN (-2200 -275) $PN 1
J 0
(-2188 -263);
DISPLAY 0.787234 (-2188 -263);
FORCEPROP 1 LASTPIN (-2000 -275) $PN 2
J 0
(-2038 -263);
DISPLAY 0.787234 (-2038 -263);
FORCEPROP 2 LAST CDS_LIB pure_quanta
J 0
(-2100 -275);
PAINT MONO (-2100 -275);
DISPLAY INVISIBLE (-2100 -275);
FORCEPROP 1 LAST PACK_TYPE 0402LF
J 0
(-2200 -200);
DISPLAY 0.510638 (-2200 -200);
DISPLAY INVISIBLE (-2200 -200);
FORCEPROP 1 LAST WATTAGE 1/16W
J 2
(-1900 -200);
DISPLAY 0.510638 (-1900 -200);
DISPLAY INVISIBLE (-1900 -200);
FORCEPROP 1 LAST PATH I94
J 0
(-2150 -125);
DISPLAY 0.978723 (-2150 -125);
PAINT WHITE (-2150 -125);
DISPLAY INVISIBLE (-2150 -125);
FORCEPROP 2 LAST CDS_LOCATION R268
J 0
(-2150 -75);
DISPLAY 1.021277 (-2150 -75);
DISPLAY INVISIBLE (-2150 -75);
FORCEPROP 2 LAST $SEC 1
J 0
(-2150 -75);
DISPLAY 0.680851 (-2150 -75);
PAINT MONO (-2150 -75);
DISPLAY INVISIBLE (-2150 -75);
FORCEPROP 2 LAST CDS_SEC 1
J 0
(-2150 -75);
DISPLAY 1.021277 (-2150 -75);
DISPLAY INVISIBLE (-2150 -75);
FORCEADD Q_RES..1
(-2100 -150);
FORCEPROP 1 LAST PART_NUMBER CS12402FB01
J 0
(-2200 -100);
DISPLAY 0.510638 (-2200 -100);
DISPLAY INVISIBLE (-2200 -100);
FORCEPROP 1 LAST VALUE 240
J 2
(-1900 -150);
DISPLAY 0.638298 (-1900 -150);
FORCEPROP 1 LAST TOLERANCE 1%
J 0
(-1875 -150);
DISPLAY 0.638298 (-1875 -150);
FORCEPROP 1 LAST MATERIAL EMPTY
J 0
(-1775 -150);
DISPLAY 0.638298 (-1775 -150);
PAINT RED (-1775 -150);
FORCEPROP 1 LAST $LOCATION R267
J 0
(-2325 -150);
DISPLAY 0.787234 (-2325 -150);
FORCEPROP 1 LASTPIN (-2200 -150) $PN 1
J 0
(-2188 -138);
DISPLAY 0.787234 (-2188 -138);
FORCEPROP 1 LASTPIN (-2000 -150) $PN 2
J 0
(-2038 -138);
DISPLAY 0.787234 (-2038 -138);
FORCEPROP 1 LAST WATTAGE 1/16W
J 2
(-1925 -75);
DISPLAY 0.510638 (-1925 -75);
DISPLAY INVISIBLE (-1925 -75);
FORCEPROP 1 LAST PACK_TYPE 0402LF
J 0
(-2200 -75);
DISPLAY 0.510638 (-2200 -75);
DISPLAY INVISIBLE (-2200 -75);
FORCEPROP 2 LAST CDS_LIB pure_quanta
J 0
(-2100 -150);
PAINT MONO (-2100 -150);
DISPLAY INVISIBLE (-2100 -150);
FORCEPROP 1 LAST PATH I95
J 0
(-2150 0);
DISPLAY 0.978723 (-2150 0);
PAINT WHITE (-2150 0);
DISPLAY INVISIBLE (-2150 0);
FORCEPROP 2 LAST CDS_LOCATION R267
J 0
(-2150 50);
DISPLAY 1.021277 (-2150 50);
DISPLAY INVISIBLE (-2150 50);
FORCEPROP 2 LAST $SEC 1
J 0
(-2150 50);
DISPLAY 0.680851 (-2150 50);
PAINT MONO (-2150 50);
DISPLAY INVISIBLE (-2150 50);
FORCEPROP 2 LAST CDS_SEC 1
J 0
(-2150 50);
DISPLAY 1.021277 (-2150 50);
DISPLAY INVISIBLE (-2150 50);
FORCEADD Q_RES..1
(-2100 -25);
FORCEPROP 1 LAST PART_NUMBER CS12402FB01
J 0
(-2200 25);
DISPLAY 0.510638 (-2200 25);
DISPLAY INVISIBLE (-2200 25);
FORCEPROP 1 LAST VALUE 240
J 2
(-1900 -25);
DISPLAY 0.638298 (-1900 -25);
FORCEPROP 1 LAST MATERIAL EMPTY
J 0
(-1775 -25);
DISPLAY 0.638298 (-1775 -25);
PAINT RED (-1775 -25);
FORCEPROP 1 LAST TOLERANCE 1%
J 0
(-1875 -25);
DISPLAY 0.638298 (-1875 -25);
FORCEPROP 1 LAST $LOCATION R266
J 0
(-2325 -25);
DISPLAY 0.787234 (-2325 -25);
FORCEPROP 1 LASTPIN (-2200 -25) $PN 1
J 0
(-2188 -13);
DISPLAY 0.787234 (-2188 -13);
FORCEPROP 1 LASTPIN (-2000 -25) $PN 2
J 0
(-2038 -13);
DISPLAY 0.787234 (-2038 -13);
FORCEPROP 1 LAST PACK_TYPE 0402LF
J 0
(-2200 50);
DISPLAY 0.510638 (-2200 50);
DISPLAY INVISIBLE (-2200 50);
FORCEPROP 1 LAST WATTAGE 1/16W
J 2
(-1925 50);
DISPLAY 0.510638 (-1925 50);
DISPLAY INVISIBLE (-1925 50);
FORCEPROP 2 LAST CDS_LIB pure_quanta
J 0
(-2100 -25);
PAINT MONO (-2100 -25);
DISPLAY INVISIBLE (-2100 -25);
FORCEPROP 1 LAST PATH I96
J 0
(-2150 125);
DISPLAY 0.978723 (-2150 125);
PAINT WHITE (-2150 125);
DISPLAY INVISIBLE (-2150 125);
FORCEPROP 2 LAST CDS_LOCATION R266
J 0
(-2150 175);
DISPLAY 1.021277 (-2150 175);
DISPLAY INVISIBLE (-2150 175);
FORCEPROP 2 LAST $SEC 1
J 0
(-2150 175);
DISPLAY 0.680851 (-2150 175);
PAINT MONO (-2150 175);
DISPLAY INVISIBLE (-2150 175);
FORCEPROP 2 LAST CDS_SEC 1
J 0
(-2150 175);
DISPLAY 1.021277 (-2150 175);
DISPLAY INVISIBLE (-2150 175);
FORCEADD Q_RES..1
(-2100 100);
FORCEPROP 1 LAST PART_NUMBER CS12402FB01
J 0
(-2200 150);
DISPLAY 0.510638 (-2200 150);
DISPLAY INVISIBLE (-2200 150);
FORCEPROP 1 LAST MATERIAL CHIP
J 0
(-1775 100);
DISPLAY 0.638298 (-1775 100);
FORCEPROP 1 LAST VALUE 240
J 2
(-1900 100);
DISPLAY 0.638298 (-1900 100);
FORCEPROP 1 LAST TOLERANCE 1%
J 0
(-1875 100);
DISPLAY 0.638298 (-1875 100);
FORCEPROP 1 LAST $LOCATION R265
J 0
(-2325 100);
DISPLAY 0.787234 (-2325 100);
FORCEPROP 1 LASTPIN (-2200 100) $PN 1
J 0
(-2188 112);
DISPLAY 0.787234 (-2188 112);
FORCEPROP 1 LASTPIN (-2000 100) $PN 2
J 0
(-2038 112);
DISPLAY 0.787234 (-2038 112);
FORCEPROP 2 LAST CDS_LIB pure_quanta
J 0
(-2100 100);
PAINT MONO (-2100 100);
DISPLAY INVISIBLE (-2100 100);
FORCEPROP 1 LAST PACK_TYPE 0402LF
J 0
(-2200 175);
DISPLAY 0.510638 (-2200 175);
DISPLAY INVISIBLE (-2200 175);
FORCEPROP 1 LAST WATTAGE 1/16W
J 2
(-1925 175);
DISPLAY 0.510638 (-1925 175);
DISPLAY INVISIBLE (-1925 175);
FORCEPROP 1 LAST PATH I97
J 0
(-2150 250);
DISPLAY 0.978723 (-2150 250);
PAINT WHITE (-2150 250);
DISPLAY INVISIBLE (-2150 250);
FORCEPROP 2 LAST CDS_LOCATION R265
J 0
(-2150 300);
DISPLAY 1.021277 (-2150 300);
DISPLAY INVISIBLE (-2150 300);
FORCEPROP 2 LAST $SEC 1
J 0
(-2150 300);
DISPLAY 0.680851 (-2150 300);
PAINT MONO (-2150 300);
DISPLAY INVISIBLE (-2150 300);
FORCEPROP 2 LAST CDS_SEC 1
J 0
(-2150 300);
DISPLAY 1.021277 (-2150 300);
DISPLAY INVISIBLE (-2150 300);
FORCEADD Q_RES..1
(-2100 225);
FORCEPROP 1 LAST PART_NUMBER CS12402FB01
J 0
(-2200 275);
DISPLAY 0.510638 (-2200 275);
DISPLAY INVISIBLE (-2200 275);
FORCEPROP 1 LAST TOLERANCE 1%
J 0
(-1875 225);
DISPLAY 0.638298 (-1875 225);
FORCEPROP 1 LAST MATERIAL EMPTY
J 0
(-1775 225);
DISPLAY 0.638298 (-1775 225);
PAINT RED (-1775 225);
FORCEPROP 1 LAST VALUE 240
J 2
(-1900 225);
DISPLAY 0.638298 (-1900 225);
FORCEPROP 1 LAST $LOCATION R264
J 0
(-2325 225);
DISPLAY 0.787234 (-2325 225);
FORCEPROP 1 LASTPIN (-2200 225) $PN 1
J 0
(-2188 237);
DISPLAY 0.787234 (-2188 237);
FORCEPROP 1 LASTPIN (-2000 225) $PN 2
J 0
(-2038 237);
DISPLAY 0.787234 (-2038 237);
FORCEPROP 2 LAST CDS_LIB pure_quanta
J 0
(-2100 225);
PAINT MONO (-2100 225);
DISPLAY INVISIBLE (-2100 225);
FORCEPROP 1 LAST PACK_TYPE 0402LF
J 0
(-2200 300);
DISPLAY 0.510638 (-2200 300);
DISPLAY INVISIBLE (-2200 300);
FORCEPROP 1 LAST WATTAGE 1/16W
J 2
(-1900 300);
DISPLAY 0.510638 (-1900 300);
DISPLAY INVISIBLE (-1900 300);
FORCEPROP 1 LAST PATH I98
J 0
(-2150 375);
DISPLAY 0.978723 (-2150 375);
PAINT WHITE (-2150 375);
DISPLAY INVISIBLE (-2150 375);
FORCEPROP 2 LAST CDS_LOCATION R264
J 0
(-2150 425);
DISPLAY 1.021277 (-2150 425);
DISPLAY INVISIBLE (-2150 425);
FORCEPROP 2 LAST $SEC 1
J 0
(-2150 425);
DISPLAY 0.680851 (-2150 425);
PAINT MONO (-2150 425);
DISPLAY INVISIBLE (-2150 425);
FORCEPROP 2 LAST CDS_SEC 1
J 0
(-2150 425);
DISPLAY 1.021277 (-2150 425);
DISPLAY INVISIBLE (-2150 425);
FORCEADD QUANTA_TITLE_BLOCK_C..1
(6550 -1850);
FORCEPROP 0 LAST CDS_CON_LAST_MODIFIED Fri Aug 25 14:01:39 2023
J 0
(4665 -1835);
PAINT MONO (4665 -1835);
DISPLAY INVISIBLE (4665 -1835);
FORCEPROP 2 LAST CUSTOM_TXT_CDS <XR_PAGE_TITLE>
J 0
(-1340 3400);
DISPLAY 0.638298 (-1340 3400);
PAINT PINK (-1340 3400);
DISPLAY INVISIBLE (-1340 3400);
FORCEPROP 2 LAST CUSTOM_TXT_CDS <Q_NUMBER>
J 0
(5147 -1747);
DISPLAY 1.212766 (5147 -1747);
FORCEPROP 2 LAST CUSTOM_TXT_CDS <NAME_1>
J 0
(3375 -1675);
FORCEPROP 2 LAST CUSTOM_TXT_CDS <Q_REV>
J 0
(6366 -1747);
DISPLAY 1.212766 (6366 -1747);
FORCEPROP 2 LAST CUSTOM_TXT_CDS <CON_PAGE_NUM> OF <CON_TOTAL_PAGES>
J 0
(6104 -1832);
DISPLAY 0.978723 (6104 -1832);
FORCEPROP 2 LAST CUSTOM_TXT_CDS <NAME_2>
J 0
(3375 -1800);
FORCEPROP 2 LAST CUSTOM_TXT_CDS <Q_PROJ>
J 0
(4168 -1748);
DISPLAY 1.212766 (4168 -1748);
FORCEPROP 2 LAST CUSTOM_TXT_CDS <CON_LAST_MODIFIED>
J 0
(4665 -1835);
DISPLAY 0.978723 (4665 -1835);
FORCEPROP 1 LAST Q_TITLE SPR CPU0 & 1- HW STRAPS
J 0
(-2716 -1849);
DISPLAY 2.446809 (-2716 -1849);
PAINT GREEN (-2716 -1849);
FORCEPROP 1 LAST Q_DEPT 
J 1
(2787 -1801);
DISPLAY 1.957447 (2787 -1801);
PAINT GREEN (2787 -1801);
FORCEPROP 2 LAST CDS_XR_PAGE_TITLE CR-119 : @S9S_MB_2U_LIB.S9S_MB_2U(SCH_1):PAGE119
J 0
(-1340 3400);
DISPLAY 0.638298 (-1340 3400);
PAINT PINK (-1340 3400);
DISPLAY INVISIBLE (-1340 3400);
FORCEPROP 2 LAST PAGE_BORDER TRUE
J 0
(-1340 3400);
DISPLAY 0.638298 (-1340 3400);
PAINT PINK (-1340 3400);
DISPLAY INVISIBLE (-1340 3400);
FORCEPROP 1 LAST COMMENT_BODY TRUE
J 0
(6562 -1863);
DISPLAY 0.978723 (6562 -1863);
PAINT GREEN (6562 -1863);
DISPLAY INVISIBLE (6562 -1863);
FORCEPROP 1 LAST CDS_LMAN_SYM_OUTLINE -9475,6775,100,-125
J 0
(6550 -1850);
DISPLAY 0.468085 (6550 -1850);
PAINT GREEN (6550 -1850);
DISPLAY INVISIBLE (6550 -1850);
FORCEPROP 2 LAST CDS_LIB pure_quanta
J 0
(6550 -1850);
PAINT MONO (6550 -1850);
DISPLAY INVISIBLE (6550 -1850);
FORCEADD DNS..2
(300 2850);
PAINT RED (300 2850);
FORCEPROP 2 LAST CDS_LIB mstr_misc
J 0
(300 2850);
PAINT MONO (300 2850);
DISPLAY INVISIBLE (300 2850);
FORCEPROP 1 LAST COMMENT_BODY TRUE
R 1
J 0
(375 2625);
DISPLAY 0.872340 (375 2625);
PAINT GREEN (375 2625);
DISPLAY INVISIBLE (375 2625);
FORCEADD DNS..2
(-2050 2450);
PAINT RED (-2050 2450);
FORCEPROP 2 LAST CDS_LIB mstr_misc
J 0
(-2050 2450);
PAINT MONO (-2050 2450);
DISPLAY INVISIBLE (-2050 2450);
FORCEPROP 1 LAST COMMENT_BODY TRUE
R 1
J 0
(-1975 2225);
DISPLAY 0.872340 (-1975 2225);
PAINT GREEN (-1975 2225);
DISPLAY INVISIBLE (-1975 2225);
FORCEADD DNS..2
(300 2975);
PAINT RED (300 2975);
FORCEPROP 2 LAST CDS_LIB mstr_misc
J 0
(300 2975);
PAINT MONO (300 2975);
DISPLAY INVISIBLE (300 2975);
FORCEPROP 1 LAST COMMENT_BODY TRUE
R 1
J 0
(375 2750);
DISPLAY 0.872340 (375 2750);
PAINT GREEN (375 2750);
DISPLAY INVISIBLE (375 2750);
FORCEADD DNS..2
(-2075 350);
PAINT RED (-2075 350);
FORCEPROP 2 LAST CDS_LIB mstr_misc
J 0
(-2075 350);
PAINT MONO (-2075 350);
DISPLAY INVISIBLE (-2075 350);
FORCEPROP 1 LAST COMMENT_BODY TRUE
R 1
J 0
(-2000 125);
DISPLAY 0.872340 (-2000 125);
PAINT GREEN (-2000 125);
DISPLAY INVISIBLE (-2000 125);
FORCEADD DNS..2
(-2050 2825);
PAINT RED (-2050 2825);
FORCEPROP 2 LAST CDS_LIB mstr_misc
J 0
(-2050 2825);
PAINT MONO (-2050 2825);
DISPLAY INVISIBLE (-2050 2825);
FORCEPROP 1 LAST COMMENT_BODY TRUE
R 1
J 0
(-1975 2600);
DISPLAY 0.872340 (-1975 2600);
PAINT GREEN (-1975 2600);
DISPLAY INVISIBLE (-1975 2600);
FORCEADD DNS..2
(-2075 -275);
PAINT RED (-2075 -275);
FORCEPROP 2 LAST CDS_LIB mstr_misc
J 0
(-2075 -275);
DISPLAY INVISIBLE (-2075 -275);
FORCEPROP 1 LAST COMMENT_BODY TRUE
R 1
J 0
(-2000 -500);
DISPLAY 0.872340 (-2000 -500);
PAINT GREEN (-2000 -500);
DISPLAY INVISIBLE (-2000 -500);
FORCEADD DNS..2
(-2075 -650);
PAINT RED (-2075 -650);
FORCEPROP 2 LAST CDS_LIB mstr_misc
J 0
(-2075 -650);
PAINT MONO (-2075 -650);
DISPLAY INVISIBLE (-2075 -650);
FORCEPROP 1 LAST COMMENT_BODY TRUE
R 1
J 0
(-2000 -875);
DISPLAY 0.872340 (-2000 -875);
PAINT GREEN (-2000 -875);
DISPLAY INVISIBLE (-2000 -875);
FORCEADD DNS..2
(-2050 2950);
PAINT RED (-2050 2950);
FORCEPROP 2 LAST CDS_LIB mstr_misc
J 0
(-2050 2950);
PAINT MONO (-2050 2950);
DISPLAY INVISIBLE (-2050 2950);
FORCEPROP 1 LAST COMMENT_BODY TRUE
R 1
J 0
(-1975 2725);
DISPLAY 0.872340 (-1975 2725);
PAINT GREEN (-1975 2725);
DISPLAY INVISIBLE (-1975 2725);
FORCEADD DNS..2
(-2075 225);
PAINT RED (-2075 225);
FORCEPROP 2 LAST CDS_LIB mstr_misc
J 0
(-2075 225);
DISPLAY INVISIBLE (-2075 225);
FORCEPROP 1 LAST COMMENT_BODY TRUE
R 1
J 0
(-2000 0);
DISPLAY 0.872340 (-2000 0);
PAINT GREEN (-2000 0);
DISPLAY INVISIBLE (-2000 0);
FORCEADD DNS..2
(-2050 3200);
PAINT RED (-2050 3200);
FORCEPROP 2 LAST CDS_LIB mstr_misc
J 0
(-2050 3200);
DISPLAY INVISIBLE (-2050 3200);
FORCEPROP 1 LAST COMMENT_BODY TRUE
R 1
J 0
(-1975 2975);
DISPLAY 0.872340 (-1975 2975);
PAINT GREEN (-1975 2975);
DISPLAY INVISIBLE (-1975 2975);
FORCEADD DNS..2
(300 3100);
PAINT RED (300 3100);
FORCEPROP 2 LAST CDS_LIB mstr_misc
J 0
(300 3100);
PAINT MONO (300 3100);
DISPLAY INVISIBLE (300 3100);
FORCEPROP 1 LAST COMMENT_BODY TRUE
R 1
J 0
(375 2875);
DISPLAY 0.872340 (375 2875);
PAINT GREEN (375 2875);
DISPLAY INVISIBLE (375 2875);
FORCEADD DESIGN_NOTE..1
(-1400 950);
FORCEPROP 0 LAST L1 240 OHM FOR 2S
J 0
(-1575 825);
DISPLAY 0.680851 (-1575 825);
FORCEPROP 0 LAST L2 150 OHM FOR 4S/8S PLATFORM
J 0
(-1575 750);
DISPLAY 0.680851 (-1575 750);
FORCEPROP 2 LAST CDS_LIB logical_power
J 0
(-1400 950);
DISPLAY INVISIBLE (-1400 950);
FORCEPROP 1 LAST COMMENT_BODY TRUE
J 0
(-1375 1050);
DISPLAY 0.978723 (-1375 1050);
DISPLAY INVISIBLE (-1375 1050);
FORCEADD DNS..2
(-2075 -150);
PAINT RED (-2075 -150);
FORCEPROP 2 LAST CDS_LIB mstr_misc
J 0
(-2075 -150);
PAINT MONO (-2075 -150);
DISPLAY INVISIBLE (-2075 -150);
FORCEPROP 1 LAST COMMENT_BODY TRUE
R 1
J 0
(-2000 -375);
DISPLAY 0.872340 (-2000 -375);
PAINT GREEN (-2000 -375);
DISPLAY INVISIBLE (-2000 -375);
FORCEADD DNS..2
(275 125);
PAINT RED (275 125);
FORCEPROP 2 LAST CDS_LIB mstr_misc
J 0
(275 125);
PAINT MONO (275 125);
DISPLAY INVISIBLE (275 125);
FORCEPROP 1 LAST COMMENT_BODY TRUE
R 1
J 0
(350 -100);
DISPLAY 0.872340 (350 -100);
PAINT GREEN (350 -100);
DISPLAY INVISIBLE (350 -100);
FORCEADD DNS..2
(-2075 600);
PAINT RED (-2075 600);
FORCEPROP 2 LAST CDS_LIB mstr_misc
J 0
(-2075 600);
PAINT MONO (-2075 600);
DISPLAY INVISIBLE (-2075 600);
FORCEPROP 1 LAST COMMENT_BODY TRUE
R 1
J 0
(-2000 375);
DISPLAY 0.872340 (-2000 375);
PAINT GREEN (-2000 375);
DISPLAY INVISIBLE (-2000 375);
FORCEADD DNS..2
(-2050 3450);
PAINT RED (-2050 3450);
FORCEPROP 2 LAST CDS_LIB mstr_misc
J 0
(-2050 3450);
PAINT MONO (-2050 3450);
DISPLAY INVISIBLE (-2050 3450);
FORCEPROP 1 LAST COMMENT_BODY TRUE
R 1
J 0
(-1975 3225);
DISPLAY 0.872340 (-1975 3225);
PAINT GREEN (-1975 3225);
DISPLAY INVISIBLE (-1975 3225);
FORCEADD DNS..2
(-2075 -775);
PAINT RED (-2075 -775);
FORCEPROP 2 LAST CDS_LIB mstr_misc
J 0
(-2075 -775);
PAINT MONO (-2075 -775);
DISPLAY INVISIBLE (-2075 -775);
FORCEPROP 1 LAST COMMENT_BODY TRUE
R 1
J 0
(-2000 -1000);
DISPLAY 0.872340 (-2000 -1000);
PAINT GREEN (-2000 -1000);
DISPLAY INVISIBLE (-2000 -1000);
FORCEADD DNS..2
(-2075 -25);
PAINT RED (-2075 -25);
FORCEPROP 2 LAST CDS_LIB mstr_misc
J 0
(-2075 -25);
PAINT MONO (-2075 -25);
DISPLAY INVISIBLE (-2075 -25);
FORCEPROP 1 LAST COMMENT_BODY TRUE
R 1
J 0
(-2000 -250);
DISPLAY 0.872340 (-2000 -250);
PAINT GREEN (-2000 -250);
DISPLAY INVISIBLE (-2000 -250);
FORCEADD DNS..2
(275 0);
PAINT RED (275 0);
FORCEPROP 2 LAST CDS_LIB mstr_misc
J 0
(275 0);
PAINT MONO (275 0);
DISPLAY INVISIBLE (275 0);
FORCEPROP 1 LAST COMMENT_BODY TRUE
R 1
J 0
(350 -225);
DISPLAY 0.872340 (350 -225);
PAINT GREEN (350 -225);
DISPLAY INVISIBLE (350 -225);
FORCEADD DNS..2
(275 250);
PAINT RED (275 250);
FORCEPROP 2 LAST CDS_LIB mstr_misc
J 0
(275 250);
PAINT MONO (275 250);
DISPLAY INVISIBLE (275 250);
FORCEPROP 1 LAST COMMENT_BODY TRUE
R 1
J 0
(350 25);
DISPLAY 0.872340 (350 25);
PAINT GREEN (350 25);
DISPLAY INVISIBLE (350 25);
FORCEADD DNS..2
(-2075 475);
PAINT RED (-2075 475);
FORCEPROP 2 LAST CDS_LIB mstr_misc
J 0
(-2075 475);
PAINT MONO (-2075 475);
DISPLAY INVISIBLE (-2075 475);
FORCEPROP 1 LAST COMMENT_BODY TRUE
R 1
J 0
(-2000 250);
DISPLAY 0.872340 (-2000 250);
PAINT GREEN (-2000 250);
DISPLAY INVISIBLE (-2000 250);
FORCEADD DNS..2
(-2050 2325);
PAINT RED (-2050 2325);
FORCEPROP 2 LAST CDS_LIB mstr_misc
J 0
(-2050 2325);
PAINT MONO (-2050 2325);
DISPLAY INVISIBLE (-2050 2325);
FORCEPROP 1 LAST COMMENT_BODY TRUE
R 1
J 0
(-1975 2100);
DISPLAY 0.872340 (-1975 2100);
PAINT GREEN (-1975 2100);
DISPLAY INVISIBLE (-1975 2100);
FORCEADD DNS..2
(-2050 3075);
PAINT RED (-2050 3075);
FORCEPROP 2 LAST CDS_LIB mstr_misc
J 0
(-2050 3075);
PAINT MONO (-2050 3075);
DISPLAY INVISIBLE (-2050 3075);
FORCEPROP 1 LAST COMMENT_BODY TRUE
R 1
J 0
(-1975 2850);
DISPLAY 0.872340 (-1975 2850);
PAINT GREEN (-1975 2850);
DISPLAY INVISIBLE (-1975 2850);
FORCEADD DNS..2
(275 -125);
PAINT RED (275 -125);
FORCEPROP 2 LAST CDS_LIB mstr_misc
J 0
(275 -125);
PAINT MONO (275 -125);
DISPLAY INVISIBLE (275 -125);
FORCEPROP 1 LAST COMMENT_BODY TRUE
R 1
J 0
(350 -350);
DISPLAY 0.872340 (350 -350);
PAINT GREEN (350 -350);
DISPLAY INVISIBLE (350 -350);
FORCEADD DNS..2
(-2050 1925);
PAINT RED (-2050 1925);
FORCEPROP 2 LAST CDS_LIB mstr_misc
J 0
(-2050 1925);
PAINT MONO (-2050 1925);
DISPLAY INVISIBLE (-2050 1925);
FORCEPROP 1 LAST COMMENT_BODY TRUE
R 1
J 0
(-1975 1700);
DISPLAY 0.872340 (-1975 1700);
PAINT GREEN (-1975 1700);
DISPLAY INVISIBLE (-1975 1700);
FORCEADD DNS..2
(-2075 -1225);
PAINT RED (-2075 -1225);
FORCEPROP 2 LAST CDS_LIB mstr_misc
J 0
(-2075 -1225);
PAINT MONO (-2075 -1225);
DISPLAY INVISIBLE (-2075 -1225);
FORCEPROP 1 LAST COMMENT_BODY TRUE
R 1
J 0
(-2000 -1450);
DISPLAY 0.872340 (-2000 -1450);
PAINT GREEN (-2000 -1450);
DISPLAY INVISIBLE (-2000 -1450);
FORCEADD DESIGN_NOTE..1
(-1375 3925);
FORCEPROP 0 LAST L1 240 OHM FOR 2S
J 0
(-1550 3800);
DISPLAY 0.680851 (-1550 3800);
FORCEPROP 0 LAST L2 150 OHM FOR 4S/8S PLATFORM
J 0
(-1550 3725);
DISPLAY 0.680851 (-1550 3725);
FORCEPROP 2 LAST CDS_LIB logical_power
J 0
(-1375 3925);
DISPLAY INVISIBLE (-1375 3925);
FORCEPROP 1 LAST COMMENT_BODY TRUE
J 0
(-1350 4025);
DISPLAY 0.978723 (-1350 4025);
DISPLAY INVISIBLE (-1350 4025);
FORCEADD DNS..2
(300 3225);
PAINT RED (300 3225);
FORCEPROP 2 LAST CDS_LIB mstr_misc
J 0
(300 3225);
PAINT MONO (300 3225);
DISPLAY INVISIBLE (300 3225);
FORCEPROP 1 LAST COMMENT_BODY TRUE
R 1
J 0
(375 3000);
DISPLAY 0.872340 (375 3000);
PAINT GREEN (375 3000);
DISPLAY INVISIBLE (375 3000);
FORCEADD DESIGN_NOTE..1
(2700 4425);
FORCEPROP 0 LAST S1 JP12: CPU0 TXT_PLT ENABLE
J 0
(2500 4275);
DISPLAY 1.021277 (2500 4275);
PAINT WHITE (2500 4275);
FORCEPROP 0 LAST S SW3 BIT2: CPU0 BUILT IN SELF TEST
J 0
(4450 4275);
DISPLAY 1.021277 (4450 4275);
PAINT WHITE (4450 4275);
FORCEPROP 2 LAST CDS_LIB logical_power
J 0
(2700 4425);
PAINT MONO (2700 4425);
DISPLAY INVISIBLE (2700 4425);
FORCEPROP 1 LAST COMMENT_BODY TRUE
J 0
(2725 4525);
DISPLAY 0.978723 (2725 4525);
DISPLAY INVISIBLE (2725 4525);
FORCEADD DESIGN_NOTE..1
(2675 50);
FORCEPROP 0 LAST S SW4 BIT2: CPU1 BUILT IN SELF TEST
J 0
(4425 -100);
DISPLAY 1.021277 (4425 -100);
PAINT WHITE (4425 -100);
FORCEPROP 0 LAST S1 SW4 BIT1: CPU1 TXT_PLT ENABLE
J 0
(2475 -100);
DISPLAY 1.021277 (2475 -100);
PAINT WHITE (2475 -100);
FORCEPROP 2 LAST CDS_LIB logical_power
J 0
(2675 50);
PAINT MONO (2675 50);
DISPLAY INVISIBLE (2675 50);
FORCEPROP 1 LAST COMMENT_BODY TRUE
J 0
(2700 150);
DISPLAY 0.978723 (2700 150);
DISPLAY INVISIBLE (2700 150);
FORCEADD DNS..2
(300 3350);
PAINT RED (300 3350);
FORCEPROP 2 LAST CDS_LIB mstr_misc
J 0
(300 3350);
PAINT MONO (300 3350);
DISPLAY INVISIBLE (300 3350);
FORCEPROP 1 LAST COMMENT_BODY TRUE
R 1
J 0
(375 3125);
DISPLAY 0.872340 (375 3125);
PAINT GREEN (375 3125);
DISPLAY INVISIBLE (375 3125);
FORCEADD DNS..2
(2950 -1275);
PAINT RED (2950 -1275);
FORCEPROP 2 LAST CDS_LIB mstr_misc
J 0
(2950 -1275);
DISPLAY INVISIBLE (2950 -1275);
FORCEPROP 1 LAST COMMENT_BODY TRUE
R 1
J 0
(3025 -1500);
DISPLAY 0.872340 (3025 -1500);
PAINT GREEN (3025 -1500);
DISPLAY INVISIBLE (3025 -1500);
FORCEADD DNS..2
(2975 3025);
PAINT RED (2975 3025);
FORCEPROP 2 LAST CDS_LIB mstr_misc
J 0
(2975 3025);
DISPLAY INVISIBLE (2975 3025);
FORCEPROP 1 LAST COMMENT_BODY TRUE
R 1
J 0
(3050 2800);
DISPLAY 0.872340 (3050 2800);
PAINT GREEN (3050 2800);
DISPLAY INVISIBLE (3050 2800);
FORCEADD DNS..2
(2975 3350);
PAINT RED (2975 3350);
FORCEPROP 2 LAST CDS_LIB mstr_misc
J 0
(2975 3350);
DISPLAY INVISIBLE (2975 3350);
FORCEPROP 1 LAST COMMENT_BODY TRUE
R 1
J 0
(3050 3125);
DISPLAY 0.872340 (3050 3125);
PAINT GREEN (3050 3125);
DISPLAY INVISIBLE (3050 3125);
FORCEADD DNS..2
(2950 -950);
PAINT RED (2950 -950);
FORCEPROP 2 LAST CDS_LIB mstr_misc
J 0
(2950 -950);
DISPLAY INVISIBLE (2950 -950);
FORCEPROP 1 LAST COMMENT_BODY TRUE
R 1
J 0
(3025 -1175);
DISPLAY 0.872340 (3025 -1175);
PAINT GREEN (3025 -1175);
DISPLAY INVISIBLE (3025 -1175);
FORCEADD DNS..2
(5075 3000);
PAINT RED (5075 3000);
FORCEPROP 2 LAST CDS_LIB mstr_misc
J 0
(5075 3000);
DISPLAY INVISIBLE (5075 3000);
FORCEPROP 1 LAST COMMENT_BODY TRUE
R 1
J 0
(5150 2775);
DISPLAY 0.872340 (5150 2775);
PAINT GREEN (5150 2775);
DISPLAY INVISIBLE (5150 2775);
FORCEADD DNS..2
(5075 3325);
PAINT RED (5075 3325);
FORCEPROP 2 LAST CDS_LIB mstr_misc
J 0
(5075 3325);
DISPLAY INVISIBLE (5075 3325);
FORCEPROP 1 LAST COMMENT_BODY TRUE
R 1
J 0
(5150 3100);
DISPLAY 0.872340 (5150 3100);
PAINT GREEN (5150 3100);
DISPLAY INVISIBLE (5150 3100);
FORCEADD DNS..2
(5050 -1300);
PAINT RED (5050 -1300);
FORCEPROP 2 LAST CDS_LIB mstr_misc
J 0
(5050 -1300);
DISPLAY INVISIBLE (5050 -1300);
FORCEPROP 1 LAST COMMENT_BODY TRUE
R 1
J 0
(5125 -1525);
DISPLAY 0.872340 (5125 -1525);
PAINT GREEN (5125 -1525);
DISPLAY INVISIBLE (5125 -1525);
FORCEADD DNS..2
(5050 -975);
PAINT RED (5050 -975);
FORCEPROP 2 LAST CDS_LIB mstr_misc
J 0
(5050 -975);
DISPLAY INVISIBLE (5050 -975);
FORCEPROP 1 LAST COMMENT_BODY TRUE
R 1
J 0
(5125 -1200);
DISPLAY 0.872340 (5125 -1200);
PAINT GREEN (5125 -1200);
DISPLAY INVISIBLE (5125 -1200);
WIRE 16 -1 (2950 -825)(2950 -675);
WIRE 16 -1 (2975 3475)(2975 3625);
WIRE 16 -1 (5075 3450)(5075 3600);
WIRE 16 -1 (-2375 3775)(-2375 3575);
WIRE 16 -1 (-2400 800)(-2400 600);
WIRE 16 -1 (-2400 -1050)(-2400 -1225);
WIRE 16 -1 (-50 2325)(-50 2250);
WIRE 16 -1 (-75 -675)(-75 -775);
WIRE 16 -1 (-2375 2100)(-2375 1925);
WIRE 16 -1 (5050 -850)(5050 -700);
WIRE 16 -1 (5050 -1375)(5050 -1475);
WIRE 16 -1 (2950 -1350)(2950 -1450);
WIRE 16 -1 (2975 2950)(2975 2850);
WIRE 16 -1 (5075 2925)(5075 2825);
WIRE 16 -1 (-75 -125)(-75 -225);
WIRE 16 -1 (-75 0)(-75 -125);
WIRE 16 -1 (-75 -125)(150 -125);
WIRE 16 -1 (-50 2850)(-50 2750);
WIRE 16 -1 (-50 2975)(-50 2850);
WIRE 16 -1 (-50 2850)(175 2850);
WIRE 16 2175 (2625 3825)(6375 3825);
WIRE 16 2175 (6375 3825)(6375 2725);
WIRE 16 2175 (2625 3825)(2625 2725);
WIRE 16 2175 (2625 2725)(6375 2725);
WIRE 16 -1 (5075 3200)(5075 3250);
WIRE 16 -1 (5075 3200)(5950 3200);
FORCEPROP 2 LAST SIG_NAME PD_CPU0_BIST_ENABLE
J 0
(5215 3210);
DISPLAY 0.680851 (5215 3210);
PAINT WHITE (5215 3210);
WIRE 16 -1 (5075 3125)(5075 3200);
WIRE 16 -1 (5050 -1100)(5050 -1050);
WIRE 16 -1 (5050 -1100)(5925 -1100);
FORCEPROP 2 LAST SIG_NAME PD_CPU1_BIST_ENABLE
J 0
(5190 -1090);
DISPLAY 0.680851 (5190 -1090);
PAINT WHITE (5190 -1090);
WIRE 16 -1 (5050 -1175)(5050 -1100);
WIRE 16 273 (6375 1175)(6375 1400);
WIRE 16 273 (6375 1400)(6375 1650);
WIRE 16 273 (2175 1400)(6375 1400);
WIRE 16 273 (2175 1400)(2175 1650);
WIRE 16 273 (2175 1650)(6375 1650);
WIRE 16 273 (6375 1650)(6375 1900);
WIRE 16 273 (2175 1175)(2175 1400);
WIRE 16 273 (2175 1175)(6375 1175);
WIRE 16 273 (6375 925)(6375 1175);
WIRE 16 273 (6375 650)(6375 925);
WIRE 16 273 (2175 1175)(2175 925);
WIRE 16 273 (2175 925)(6375 925);
WIRE 16 273 (6375 1900)(6375 2150);
WIRE 16 273 (2175 1900)(2175 1650);
WIRE 16 273 (2175 1900)(6375 1900);
WIRE 16 273 (2175 2150)(2175 1900);
WIRE 16 273 (2175 2150)(6375 2150);
WIRE 16 273 (6375 2150)(6375 2400);
WIRE 16 273 (2175 650)(2175 925);
WIRE 16 273 (2175 650)(6375 650);
WIRE 16 273 (6375 425)(6375 650);
WIRE 16 273 (6375 200)(6375 425);
WIRE 16 273 (2175 650)(2175 425);
WIRE 16 273 (2175 425)(6375 425);
WIRE 16 273 (6375 2400)(6375 2600);
WIRE 16 273 (2175 2400)(2175 2150);
WIRE 16 273 (2175 2400)(6375 2400);
WIRE 16 273 (2175 2600)(2175 2400);
WIRE 16 273 (6375 2600)(4425 2600);
WIRE 16 273 (2175 200)(2175 425);
WIRE 16 273 (4425 200)(6375 200);
WIRE 16 273 (4425 200)(4425 2600);
WIRE 16 273 (4000 200)(4425 200);
WIRE 16 273 (2175 200)(3125 200);
WIRE 16 273 (4000 2600)(4425 2600);
WIRE 16 273 (4000 200)(4000 2600);
WIRE 16 273 (2175 2600)(3125 2600);
WIRE 16 273 (3125 200)(3125 2600);
WIRE 16 273 (3125 2600)(3550 2600);
WIRE 16 273 (3550 2600)(4000 2600);
WIRE 16 273 (3125 200)(3550 200);
WIRE 16 273 (3550 200)(4000 200);
WIRE 16 273 (3550 200)(3550 2600);
WIRE 16 3135 (2475 4100)(2475 3975);
WIRE 16 3135 (2475 4225)(2475 4100);
WIRE 16 3135 (2475 3975)(2800 3975);
WIRE 16 3135 (2800 3975)(4325 3975);
WIRE 16 3135 (2475 4100)(4325 4100);
WIRE 16 3135 (4325 3975)(4325 4100);
WIRE 16 3135 (4325 4100)(4325 4225);
WIRE 16 3135 (2800 4225)(2800 3975);
WIRE 16 3135 (2475 4225)(2800 4225);
WIRE 16 3135 (2800 4225)(4325 4225);
WIRE 16 -1 (2975 3225)(2975 3150);
WIRE 16 -1 (2975 3275)(2975 3225);
WIRE 16 -1 (2975 3225)(3900 3225);
FORCEPROP 2 LAST SIG_NAME PD_CPU0_TXT_PLTEN
J 0
(3165 3235);
DISPLAY 0.680851 (3165 3235);
PAINT WHITE (3165 3235);
WIRE 16 3135 (2450 -300)(2450 -425);
WIRE 16 3135 (2450 -425)(2775 -425);
WIRE 16 3135 (2775 -425)(4300 -425);
WIRE 16 3135 (2450 -175)(2450 -300);
WIRE 16 3135 (2450 -300)(4300 -300);
WIRE 16 3135 (4300 -425)(4300 -300);
WIRE 16 3135 (4300 -300)(4300 -175);
WIRE 16 3135 (2450 -175)(2775 -175);
WIRE 16 3135 (2775 -175)(2775 -425);
WIRE 16 3135 (2775 -175)(4300 -175);
WIRE 16 2175 (2575 -1550)(6325 -1550);
WIRE 16 2175 (6325 -450)(6325 -1550);
WIRE 16 2175 (2575 -450)(2575 -1550);
WIRE 16 2175 (2575 -450)(6325 -450);
WIRE 16 -1 (2950 -1025)(2950 -1075);
WIRE 16 -1 (2950 -1075)(2950 -1150);
WIRE 16 -1 (2950 -1075)(3875 -1075);
FORCEPROP 2 LAST SIG_NAME PD_CPU1_TXT_PLTEN
J 0
(3140 -1065);
DISPLAY 0.680851 (3140 -1065);
PAINT WHITE (3140 -1065);
WIRE 16 3135 (4425 4100)(4425 3975);
WIRE 16 3135 (4425 4225)(4425 4100);
WIRE 16 3135 (4425 3975)(4700 3975);
WIRE 16 3135 (4700 3975)(6275 3975);
WIRE 16 3135 (6275 3975)(6275 4100);
WIRE 16 3135 (4425 4100)(6275 4100);
WIRE 16 3135 (6275 4100)(6275 4225);
WIRE 16 3135 (4700 4225)(4700 3975);
WIRE 16 3135 (4425 4225)(4700 4225);
WIRE 16 3135 (4700 4225)(6275 4225);
WIRE 16 -1 (350 2250)(1500 2250);
FORCEPROP 2 LAST SIG_NAME FM_CPU0_PKGID0
J 0
(775 2260);
DISPLAY 0.680851 (775 2260);
PAINT WHITE (775 2260);
WIRE 16 -1 (350 2125)(1500 2125);
FORCEPROP 2 LAST SIG_NAME FM_CPU0_PKGID1
J 0
(775 2135);
DISPLAY 0.680851 (775 2135);
PAINT WHITE (775 2135);
WIRE 16 -1 (350 2000)(1500 2000);
FORCEPROP 2 LAST SIG_NAME FM_CPU0_PKGID2
J 0
(775 2010);
DISPLAY 0.680851 (775 2010);
PAINT WHITE (775 2010);
WIRE 16 -1 (325 -1025)(1475 -1025);
FORCEPROP 2 LAST SIG_NAME FM_CPU1_PKGID2
J 0
(750 -1015);
DISPLAY 0.680851 (750 -1015);
PAINT WHITE (750 -1015);
WIRE 16 -1 (325 -900)(1475 -900);
FORCEPROP 2 LAST SIG_NAME FM_CPU1_PKGID1
J 0
(750 -890);
DISPLAY 0.680851 (750 -890);
PAINT WHITE (750 -890);
WIRE 16 -1 (325 -775)(1475 -775);
FORCEPROP 2 LAST SIG_NAME FM_CPU1_PKGID0
J 0
(750 -765);
DISPLAY 0.680851 (750 -765);
PAINT WHITE (750 -765);
WIRE 16 -1 (325 -1275)(1475 -1275);
FORCEPROP 2 LAST SIG_NAME FM_CPU1_PROC_ID1
J 0
(750 -1265);
DISPLAY 0.680851 (750 -1265);
PAINT WHITE (750 -1265);
WIRE 16 -1 (325 -1150)(1475 -1150);
FORCEPROP 2 LAST SIG_NAME FM_CPU1_PROC_ID0
J 0
(750 -1140);
DISPLAY 0.680851 (750 -1140);
PAINT WHITE (750 -1140);
WIRE 16 -1 (-1975 1925)(-750 1925);
FORCEPROP 2 LAST SIG_NAME PU_TAP_ODT_CPU0_EN
J 0
(-1475 1935);
DISPLAY 0.680851 (-1475 1935);
PAINT WHITE (-1475 1935);
WIRE 16 -1 (-2000 -1225)(-800 -1225);
FORCEPROP 2 LAST SIG_NAME PU_TAP_ODT_CPU1_EN
J 0
(-1525 -1215);
DISPLAY 0.680851 (-1525 -1215);
PAINT WHITE (-1525 -1215);
WIRE 16 -1 (-2000 -25)(-800 -25);
FORCEPROP 2 LAST SIG_NAME PU_CPU1_SOCKET_ID1
J 0
(-1525 -15);
DISPLAY 0.680851 (-1525 -15);
PAINT WHITE (-1525 -15);
WIRE 16 -1 (-2000 475)(-800 475);
FORCEPROP 2 LAST SIG_NAME PU_CPU1_SAFE_MODE_BOOT
J 0
(-1525 485);
DISPLAY 0.680851 (-1525 485);
PAINT WHITE (-1525 485);
WIRE 16 -1 (-2000 600)(-800 600);
FORCEPROP 2 LAST SIG_NAME PU_CPU1_TXT_AGENT
J 0
(-1525 610);
DISPLAY 0.680851 (-1525 610);
PAINT WHITE (-1525 610);
WIRE 16 -1 (-2000 350)(-800 350);
FORCEPROP 2 LAST SIG_NAME PU_CPU1_FRMAGENT
J 0
(-1525 360);
DISPLAY 0.680851 (-1525 360);
PAINT WHITE (-1525 360);
WIRE 16 -1 (-1975 2950)(-750 2950);
FORCEPROP 2 LAST SIG_NAME PU_CPU0_SOCKET_ID1
J 0
(-1475 2960);
DISPLAY 0.680851 (-1475 2960);
PAINT WHITE (-1475 2960);
WIRE 16 -1 (-1975 2825)(-750 2825);
FORCEPROP 2 LAST SIG_NAME PU_CPU0_SOCKET_ID2
J 0
(-1475 2835);
DISPLAY 0.680851 (-1475 2835);
PAINT WHITE (-1475 2835);
WIRE 16 -1 (375 3350)(1625 3350);
FORCEPROP 2 LAST SIG_NAME PD_CPU0_DMIMODE_OVERRIDE
J 0
(815 3360);
DISPLAY 0.680851 (815 3360);
PAINT WHITE (815 3360);
WIRE 16 -1 (-1975 2450)(-750 2450);
FORCEPROP 2 LAST SIG_NAME PUD_XTAL_CPU0_MODE0
J 0
(-1475 2460);
DISPLAY 0.680851 (-1475 2460);
PAINT WHITE (-1475 2460);
WIRE 16 -1 (-1975 2325)(-750 2325);
FORCEPROP 2 LAST SIG_NAME PUD_XTAL_CPU0_MODE1
J 0
(-1475 2335);
DISPLAY 0.680851 (-1475 2335);
PAINT WHITE (-1475 2335);
WIRE 16 -1 (1625 3100)(375 3100);
FORCEPROP 2 LAST SIG_NAME PD_EXT_CLK_SEL_CPU0
J 0
(815 3110);
DISPLAY 0.680851 (815 3110);
PAINT WHITE (815 3110);
WIRE 16 -1 (1625 2975)(375 2975);
FORCEPROP 2 LAST SIG_NAME PUD_XTAL_CPU0_MODE0
J 0
(815 2985);
DISPLAY 0.680851 (815 2985);
PAINT WHITE (815 2985);
WIRE 16 -1 (-1975 2700)(-750 2700);
FORCEPROP 2 LAST SIG_NAME PU_CPU0_LEGACY_SKT
J 0
(-1475 2710);
DISPLAY 0.680851 (-1475 2710);
PAINT WHITE (-1475 2710);
WIRE 16 -1 (-1975 3075)(-750 3075);
FORCEPROP 2 LAST SIG_NAME PU_CPU0_SOCKET_ID0
J 0
(-1475 3085);
DISPLAY 0.680851 (-1475 3085);
PAINT WHITE (-1475 3085);
WIRE 16 -1 (-2000 -275)(-800 -275);
FORCEPROP 2 LAST SIG_NAME PU_CPU1_LEGACY_SKT
J 0
(-1525 -265);
DISPLAY 0.680851 (-1525 -265);
PAINT WHITE (-1525 -265);
WIRE 16 -1 (-2000 -650)(-800 -650);
FORCEPROP 2 LAST SIG_NAME PUD_XTAL_CPU1_MODE0
J 0
(-1525 -640);
DISPLAY 0.680851 (-1525 -640);
PAINT WHITE (-1525 -640);
WIRE 16 -1 (-2000 -775)(-800 -775);
FORCEPROP 2 LAST SIG_NAME PUD_XTAL_CPU1_MODE1
J 0
(-1525 -765);
DISPLAY 0.680851 (-1525 -765);
PAINT WHITE (-1525 -765);
WIRE 16 -1 (1625 3225)(375 3225);
FORCEPROP 2 LAST SIG_NAME PD_CPU0_ENH_MCECC_DIS
J 0
(815 3235);
DISPLAY 0.680851 (815 3235);
PAINT WHITE (815 3235);
WIRE 16 -1 (1625 2850)(375 2850);
FORCEPROP 2 LAST SIG_NAME PUD_XTAL_CPU0_MODE1
J 0
(815 2860);
DISPLAY 0.680851 (815 2860);
PAINT WHITE (815 2860);
WIRE 16 -1 (-2000 225)(-800 225);
FORCEPROP 2 LAST SIG_NAME H_CPU1_BMCINIT_LVC1
J 0
(-1525 235);
DISPLAY 0.680851 (-1525 235);
PAINT WHITE (-1525 235);
WIRE 16 -1 (-2000 100)(-800 100);
FORCEPROP 2 LAST SIG_NAME PU_CPU1_SOCKET_ID0
J 0
(-1525 110);
DISPLAY 0.680851 (-1525 110);
PAINT WHITE (-1525 110);
WIRE 16 -1 (-2000 -150)(-800 -150);
FORCEPROP 2 LAST SIG_NAME PU_CPU1_SOCKET_ID2
J 0
(-1525 -140);
DISPLAY 0.680851 (-1525 -140);
PAINT WHITE (-1525 -140);
WIRE 16 -1 (1600 -125)(350 -125);
FORCEPROP 2 LAST SIG_NAME PUD_XTAL_CPU1_MODE1
J 0
(790 -115);
DISPLAY 0.680851 (790 -115);
PAINT WHITE (790 -115);
WIRE 16 -1 (-1975 3200)(-750 3200);
FORCEPROP 2 LAST SIG_NAME H_CPU0_BMCINIT_LVC1
J 0
(-1475 3210);
DISPLAY 0.680851 (-1475 3210);
PAINT WHITE (-1475 3210);
WIRE 16 -1 (-1975 3325)(-750 3325);
FORCEPROP 2 LAST SIG_NAME PU_CPU0_FRMAGENT
J 0
(-1475 3335);
DISPLAY 0.680851 (-1475 3335);
PAINT WHITE (-1475 3335);
WIRE 16 -1 (-1975 3450)(-750 3450);
FORCEPROP 2 LAST SIG_NAME PU_CPU0_SAFE_MODE_BOOT
J 0
(-1475 3460);
DISPLAY 0.680851 (-1475 3460);
PAINT WHITE (-1475 3460);
WIRE 16 -1 (-1975 3575)(-750 3575);
FORCEPROP 2 LAST SIG_NAME PU_CPU0_TXT_AGENT
J 0
(-1475 3585);
DISPLAY 0.680851 (-1475 3585);
PAINT WHITE (-1475 3585);
WIRE 16 -1 (350 1875)(1500 1875);
FORCEPROP 2 LAST SIG_NAME FM_CPU0_PROC_ID0
J 0
(775 1885);
DISPLAY 0.680851 (775 1885);
PAINT WHITE (775 1885);
WIRE 16 -1 (350 1750)(1500 1750);
FORCEPROP 2 LAST SIG_NAME FM_CPU0_PROC_ID1
J 0
(775 1760);
DISPLAY 0.680851 (775 1760);
PAINT WHITE (775 1760);
WIRE 16 3135 (4675 -175)(4675 -425);
WIRE 16 3135 (4400 -425)(4675 -425);
WIRE 16 3135 (4400 -175)(4675 -175);
WIRE 16 3135 (4675 -425)(6250 -425);
WIRE 16 3135 (4675 -175)(6250 -175);
WIRE 16 3135 (6250 -300)(6250 -175);
WIRE 16 3135 (6250 -425)(6250 -300);
WIRE 16 3135 (4400 -175)(4400 -300);
WIRE 16 3135 (4400 -300)(4400 -425);
WIRE 16 3135 (4400 -300)(6250 -300);
WIRE 16 -1 (-2400 -775)(-2200 -775);
WIRE 16 -1 (-2400 -775)(-2400 -650);
WIRE 16 -1 (-2400 -650)(-2200 -650);
WIRE 16 -1 (-2400 -650)(-2400 -275);
WIRE 16 -1 (-2400 -275)(-2200 -275);
WIRE 16 -1 (-2400 -275)(-2400 -150);
WIRE 16 -1 (-2400 -150)(-2200 -150);
WIRE 16 -1 (-2400 -150)(-2400 -25);
WIRE 16 -1 (-2400 -25)(-2200 -25);
WIRE 16 -1 (-2400 100)(-2400 -25);
WIRE 16 -1 (-2400 100)(-2200 100);
WIRE 16 -1 (-2400 225)(-2400 100);
WIRE 16 -1 (-2400 225)(-2200 225);
WIRE 16 -1 (-2400 350)(-2400 225);
WIRE 16 -1 (-2400 350)(-2200 350);
WIRE 16 -1 (-2400 475)(-2400 350);
WIRE 16 -1 (-2400 475)(-2200 475);
WIRE 16 -1 (-2400 600)(-2400 475);
WIRE 16 -1 (-2400 600)(-2200 600);
WIRE 16 -1 (-2175 1925)(-2375 1925);
WIRE 16 -1 (-2200 -1225)(-2400 -1225);
WIRE 16 -1 (-50 1750)(150 1750);
WIRE 16 -1 (-50 1875)(-50 1750);
WIRE 16 -1 (-50 1875)(150 1875);
WIRE 16 -1 (-50 2000)(-50 1875);
WIRE 16 -1 (-50 2000)(150 2000);
WIRE 16 -1 (-50 2125)(-50 2000);
WIRE 16 -1 (-50 2125)(150 2125);
WIRE 16 -1 (-50 2250)(-50 2125);
WIRE 16 -1 (-50 2250)(150 2250);
WIRE 16 -1 (-75 0)(150 0);
WIRE 16 -1 (-75 125)(-75 0);
WIRE 16 -1 (-75 125)(150 125);
WIRE 16 -1 (-75 250)(-75 125);
WIRE 16 -1 (-75 250)(150 250);
WIRE 16 -1 (-75 375)(-75 250);
WIRE 16 -1 (-75 375)(150 375);
WIRE 16 -1 (-2375 2325)(-2175 2325);
WIRE 16 -1 (-2375 2325)(-2375 2450);
WIRE 16 -1 (-2375 2450)(-2175 2450);
WIRE 16 -1 (-2375 2450)(-2375 2700);
WIRE 16 -1 (-2375 2700)(-2175 2700);
WIRE 16 -1 (-2375 2700)(-2375 2825);
WIRE 16 -1 (-2375 2825)(-2175 2825);
WIRE 16 -1 (-2375 2825)(-2375 2950);
WIRE 16 -1 (-2375 2950)(-2175 2950);
WIRE 16 -1 (-2375 3075)(-2375 2950);
WIRE 16 -1 (-2375 3075)(-2175 3075);
WIRE 16 -1 (-2375 3200)(-2375 3075);
WIRE 16 -1 (-2375 3200)(-2175 3200);
WIRE 16 -1 (-2375 3325)(-2375 3200);
WIRE 16 -1 (-2375 3325)(-2175 3325);
WIRE 16 -1 (-2375 3450)(-2375 3325);
WIRE 16 -1 (-2375 3450)(-2175 3450);
WIRE 16 -1 (-2375 3575)(-2375 3450);
WIRE 16 -1 (-2375 3575)(-2175 3575);
WIRE 16 -1 (-50 2975)(175 2975);
WIRE 16 -1 (-50 3100)(-50 2975);
WIRE 16 -1 (-50 3100)(175 3100);
WIRE 16 -1 (-50 3225)(-50 3100);
WIRE 16 -1 (-50 3225)(175 3225);
WIRE 16 -1 (-50 3350)(-50 3225);
WIRE 16 -1 (-50 3350)(175 3350);
WIRE 16 -1 (-75 -1275)(125 -1275);
WIRE 16 -1 (-75 -1150)(-75 -1275);
WIRE 16 -1 (-75 -1150)(125 -1150);
WIRE 16 -1 (-75 -1025)(-75 -1150);
WIRE 16 -1 (-75 -1025)(125 -1025);
WIRE 16 -1 (-75 -900)(-75 -1025);
WIRE 16 -1 (-75 -900)(125 -900);
WIRE 16 -1 (-75 -775)(-75 -900);
WIRE 16 -1 (-75 -775)(125 -775);
WIRE 16 -1 (1600 0)(350 0);
FORCEPROP 2 LAST SIG_NAME PUD_XTAL_CPU1_MODE0
J 0
(790 10);
DISPLAY 0.680851 (790 10);
PAINT WHITE (790 10);
WIRE 16 -1 (1600 125)(350 125);
FORCEPROP 2 LAST SIG_NAME PD_EXT_CLK_SEL_CPU1
J 0
(790 135);
DISPLAY 0.680851 (790 135);
PAINT WHITE (790 135);
WIRE 16 -1 (1600 250)(350 250);
FORCEPROP 2 LAST SIG_NAME PD_CPU1_ENH_MCECC_DIS
J 0
(790 260);
DISPLAY 0.680851 (790 260);
PAINT WHITE (790 260);
WIRE 16 -1 (350 375)(1600 375);
FORCEPROP 0 LAST CDS_PHYS_NET_NAME PD_CPU0_DMICODE_OVERRIDE
J 0
(790 417);
PAINT MONO (790 417);
DISPLAY INVISIBLE (790 417);
FORCEPROP 2 LAST SIG_NAME PD_CPU1_DMIMODE_OVERRIDE
J 0
(790 385);
DISPLAY 0.680851 (790 385);
PAINT WHITE (790 385);
DOT 1 (4300 -300);
DOT 1 (4400 -300);
DOT 1 (6250 -300);
DOT 1 (4675 -425);
DOT 1 (2775 -175);
DOT 1 (2450 -300);
DOT 1 (2775 -425);
DOT 1 (4700 4225);
DOT 1 (4325 4100);
DOT 1 (4425 4100);
DOT 1 (6275 4100);
DOT 1 (4700 3975);
DOT 1 (2800 4225);
DOT 1 (2475 4100);
DOT 1 (2800 3975);
DOT 1 (4000 2600);
DOT 1 (2175 2400);
DOT 1 (-50 2850);
DOT 1 (-75 250);
DOT 1 (-2375 3450);
DOT 1 (-2375 3325);
DOT 1 (-50 2250);
DOT 1 (-2400 -650);
DOT 1 (-2400 -275);
DOT 1 (-2375 2450);
DOT 1 (-2375 3075);
DOT 1 (-2375 2825);
DOT 1 (-2375 2700);
DOT 1 (-2375 2950);
DOT 1 (-2375 3200);
DOT 1 (-2375 3575);
DOT 1 (-2400 475);
DOT 1 (-2400 350);
DOT 1 (-2400 600);
DOT 1 (-2400 100);
DOT 1 (-2400 -25);
DOT 1 (-2400 -150);
DOT 1 (-2400 225);
DOT 1 (-50 3225);
DOT 1 (-50 2125);
DOT 1 (-50 2000);
DOT 1 (-50 1875);
DOT 1 (-75 125);
DOT 1 (-75 0);
DOT 1 (-75 -900);
DOT 1 (-75 -1025);
DOT 1 (-75 -1150);
DOT 1 (-75 -125);
DOT 1 (-75 -775);
DOT 1 (-50 2975);
DOT 1 (-50 3100);
DOT 1 (6375 2150);
DOT 1 (6375 2400);
DOT 1 (6375 1650);
DOT 1 (6375 1900);
DOT 1 (6375 1400);
DOT 1 (6375 1175);
DOT 1 (6375 925);
DOT 1 (6375 650);
DOT 1 (6375 425);
DOT 1 (4425 200);
DOT 1 (3550 2600);
DOT 1 (2175 2150);
DOT 1 (3125 200);
DOT 1 (3550 200);
DOT 1 (2175 1650);
DOT 1 (2175 1900);
DOT 1 (2175 1400);
DOT 1 (2175 1175);
DOT 1 (2175 650);
DOT 1 (2175 425);
DOT 1 (2175 925);
DOT 1 (4675 -175);
DOT 1 (4000 200);
DOT 1 (3125 2600);
DOT 1 (2950 -1075);
DOT 1 (5050 -1100);
DOT 1 (5075 3200);
DOT 1 (2975 3225);
DOT 1 (4425 2600);
FORCENOTE
20220729 DEPOP R4262
(5150 3550) 0;
DISPLAY LEFT (5150 3550);
DISPLAY 1.063830 (5150 3550);
PAINT WHITE (5150 3550);
FORCENOTE
20220729 DEPOP R4262
(5250 -725) 0;
DISPLAY LEFT (5250 -725);
DISPLAY 1.063830 (5250 -725);
PAINT WHITE (5250 -725);
FORCENOTE
20211201 CHANGE TXT,BIST TO ENABLE
(3225 2775) 0;
DISPLAY LEFT (3225 2775);
DISPLAY 1.063830 (3225 2775);
PAINT WHITE (3225 2775);
FORCENOTE
CPU1 STRAPPING
(-2400 1250) 0;
DISPLAY LEFT (-2400 1250);
DISPLAY 3.297872 (-2400 1250);
PAINT WHITE (-2400 1250);
FORCENOTE
2-3     ENABLE (DEFAULT)
(2575 4150) 0;
DISPLAY LEFT (2575 4150);
DISPLAY 0.808511 (2575 4150);
PAINT YELLOW (2575 4150);
FORCENOTE
LEGACY_SKT
(2225 300) 0;
DISPLAY LEFT (2225 300);
DISPLAY 1.021277 (2225 300);
PAINT WHITE (2225 300);
FORCENOTE
1-2     DISABLE
(2575 4025) 0;
DISPLAY LEFT (2575 4025);
DISPLAY 0.808511 (2575 4025);
PAINT YELLOW (2575 4025);
FORCENOTE
0
(4200 300) 0;
DISPLAY LEFT (4200 300);
DISPLAY 1.021277 (4200 300);
PAINT WHITE (4200 300);
FORCENOTE
0
(4200 775) 0;
DISPLAY LEFT (4200 775);
DISPLAY 1.021277 (4200 775);
PAINT WHITE (4200 775);
FORCENOTE
001
(4150 1025) 0;
DISPLAY LEFT (4150 1025);
DISPLAY 1.021277 (4150 1025);
PAINT WHITE (4150 1025);
FORCENOTE
0
(4200 1750) 0;
DISPLAY LEFT (4200 1750);
DISPLAY 1.021277 (4200 1750);
PAINT WHITE (4200 1750);
FORCENOTE
0
(4200 525) 0;
DISPLAY LEFT (4200 525);
DISPLAY 1.021277 (4200 525);
PAINT WHITE (4200 525);
FORCENOTE
SAFE_MODE_BOOT
(2225 2000) 0;
DISPLAY LEFT (2225 2000);
DISPLAY 1.021277 (2225 2000);
PAINT WHITE (2225 2000);
FORCENOTE
CPU0 HW STRAPS
(3100 4400) 0;
DISPLAY LEFT (3100 4400);
DISPLAY 1.595745 (3100 4400);
PAINT SKYBLUE (3100 4400);
FORCENOTE
BIST_ENABLE
(2225 2250) 0;
DISPLAY LEFT (2225 2250);
DISPLAY 1.021277 (2225 2250);
PAINT WHITE (2225 2250);
FORCENOTE
TXT_AGENT
(2225 1725) 0;
DISPLAY LEFT (2225 1725);
DISPLAY 1.021277 (2225 1725);
PAINT WHITE (2225 1725);
FORCENOTE
0
(4200 2000) 0;
DISPLAY LEFT (4200 2000);
DISPLAY 1.021277 (4200 2000);
PAINT WHITE (4200 2000);
FORCENOTE
0
(4200 1250) 0;
DISPLAY LEFT (4200 1250);
DISPLAY 1.021277 (4200 1250);
PAINT WHITE (4200 1250);
FORCENOTE
FLOW
(4625 725) 0;
DISPLAY LEFT (4625 725);
DISPLAY 1.021277 (4625 725);
PAINT WHITE (4625 725);
FORCENOTE
1
(3750 1250) 0;
DISPLAY LEFT (3750 1250);
DISPLAY 1.021277 (3750 1250);
PAINT WHITE (3750 1250);
FORCENOTE
1
(3750 525) 0;
DISPLAY LEFT (3750 525);
DISPLAY 1.021277 (3750 525);
PAINT WHITE (3750 525);
FORCENOTE
0
(3750 775) 0;
DISPLAY LEFT (3750 775);
DISPLAY 1.021277 (3750 775);
PAINT WHITE (3750 775);
FORCENOTE
TXT_PLTEN
(2225 1500) 0;
DISPLAY LEFT (2225 1500);
DISPLAY 1.021277 (2225 1500);
PAINT WHITE (2225 1500);
FORCENOTE
BMCINIT
(2225 775) 0;
DISPLAY LEFT (2225 775);
DISPLAY 1.021277 (2225 775);
PAINT WHITE (2225 775);
FORCENOTE
CPU0 STRAPPING
(-2375 4225) 0;
DISPLAY LEFT (-2375 4225);
DISPLAY 3.297872 (-2375 4225);
PAINT WHITE (-2375 4225);
FORCENOTE
1
(4200 2250) 0;
DISPLAY LEFT (4200 2250);
DISPLAY 1.021277 (4200 2250);
PAINT WHITE (4200 2250);
FORCENOTE
1: CPU HAULTS UNTIL BMC RELEASES BOOT
(4475 775) 0;
DISPLAY LEFT (4475 775);
DISPLAY 1.021277 (4475 775);
PAINT WHITE (4475 775);
FORCENOTE
0: TXT DISABLED
(4475 1425) 0;
DISPLAY LEFT (4475 1425);
DISPLAY 1.021277 (4475 1425);
PAINT WHITE (4475 1425);
FORCENOTE
1
(3750 1750) 0;
DISPLAY LEFT (3750 1750);
DISPLAY 1.021277 (3750 1750);
PAINT WHITE (3750 1750);
FORCENOTE
1
(3750 1500) 0;
DISPLAY LEFT (3750 1500);
DISPLAY 1.021277 (3750 1500);
PAINT WHITE (3750 1500);
FORCENOTE
SOCKET_ID[2:0]
(2225 1025) 0;
DISPLAY LEFT (2225 1025);
DISPLAY 1.021277 (2225 1025);
PAINT WHITE (2225 1025);
FORCENOTE
FRMAGENT
(2225 1275) 0;
DISPLAY LEFT (2225 1275);
DISPLAY 1.021277 (2225 1275);
PAINT WHITE (2225 1275);
FORCENOTE
1-2    DISABLE BIST
(4475 -375) 0;
DISPLAY LEFT (4475 -375);
DISPLAY 0.808511 (4475 -375);
PAINT YELLOW (4475 -375);
FORCENOTE
DMI MODE
(4450 575) 0;
DISPLAY LEFT (4450 575);
DISPLAY 1.021277 (4450 575);
PAINT WHITE (4450 575);
FORCENOTE
1
(4200 1500) 0;
DISPLAY LEFT (4200 1500);
DISPLAY 1.021277 (4200 1500);
PAINT WHITE (4200 1500);
FORCENOTE
1
(3750 300) 0;
DISPLAY LEFT (3750 300);
DISPLAY 1.021277 (3750 300);
PAINT WHITE (3750 300);
FORCENOTE
0: NON-LEGACY. DMI3 IS NOT INITIALIZED
(4475 225) 0;
DISPLAY LEFT (4475 225);
DISPLAY 1.021277 (4475 225);
PAINT WHITE (4475 225);
FORCENOTE
BOOT MODE OPERATION
(4450 350) 0;
DISPLAY LEFT (4450 350);
DISPLAY 1.021277 (4450 350);
PAINT WHITE (4450 350);
FORCENOTE
1: F/W IS LOCAL TO THIS SOCKET'S PCH
(4475 500) 0;
DISPLAY LEFT (4475 500);
DISPLAY 1.021277 (4475 500);
PAINT WHITE (4475 500);
FORCENOTE
0: NORMAL BOOT FLOW
(4475 675) 0;
DISPLAY LEFT (4475 675);
DISPLAY 1.021277 (4475 675);
PAINT WHITE (4475 675);
FORCENOTE
LEGACY CPU = 00
(4475 1025) 0;
DISPLAY LEFT (4475 1025);
DISPLAY 1.021277 (4475 1025);
PAINT WHITE (4475 1025);
FORCENOTE
SOCKET IDENTIFIER
(4450 1100) 0;
DISPLAY LEFT (4450 1100);
DISPLAY 1.021277 (4450 1100);
PAINT WHITE (4450 1100);
FORCENOTE
0: PCIE MODE
(4475 1200) 0;
DISPLAY LEFT (4475 1200);
DISPLAY 1.021277 (4475 1200);
PAINT WHITE (4475 1200);
FORCENOTE
1: DMI MODE
(4475 1250) 0;
DISPLAY LEFT (4475 1250);
DISPLAY 1.021277 (4475 1250);
PAINT WHITE (4475 1250);
FORCENOTE
CPU DMI PORT MODE
(4450 1325) 0;
DISPLAY LEFT (4450 1325);
DISPLAY 1.021277 (4450 1325);
PAINT WHITE (4450 1325);
FORCENOTE
1: TXT ENABLED
(4475 1475) 0;
DISPLAY LEFT (4475 1475);
DISPLAY 1.021277 (4475 1475);
PAINT WHITE (4475 1475);
FORCENOTE
TXT ENABLE
(4450 1550) 0;
DISPLAY LEFT (4450 1550);
DISPLAY 1.021277 (4450 1550);
PAINT WHITE (4450 1550);
FORCENOTE
1: CPU IS TXT AGENT
(4475 1725) 0;
DISPLAY LEFT (4475 1725);
DISPLAY 1.021277 (4475 1725);
PAINT WHITE (4475 1725);
FORCENOTE
0: SAFE MODE BOOT DISABLED
(4475 1925) 0;
DISPLAY LEFT (4475 1925);
DISPLAY 1.021277 (4475 1925);
PAINT WHITE (4475 1925);
FORCENOTE
0: BIST DISABLED
(4475 2175) 0;
DISPLAY LEFT (4475 2175);
DISPLAY 1.021277 (4475 2175);
PAINT WHITE (4475 2175);
FORCENOTE
1: BIST ENABLED
(4475 2225) 0;
DISPLAY LEFT (4475 2225);
DISPLAY 1.021277 (4475 2225);
PAINT WHITE (4475 2225);
FORCENOTE
BUILT IN SELF TEST
(4450 2300) 0;
DISPLAY LEFT (4450 2300);
DISPLAY 1.021277 (4450 2300);
PAINT WHITE (4450 2300);
FORCENOTE
000
(3700 1025) 0;
DISPLAY LEFT (3700 1025);
DISPLAY 1.021277 (3700 1025);
PAINT WHITE (3700 1025);
FORCENOTE
2-3    ENABLE BIST (DEFAULT)
(4475 -250) 0;
DISPLAY LEFT (4475 -250);
DISPLAY 0.808511 (4475 -250);
PAINT YELLOW (4475 -250);
FORCENOTE
1: F/W IS LOCAL TO THIS SOCKET'S PCH
(4475 275) 0;
DISPLAY LEFT (4475 275);
DISPLAY 1.021277 (4475 275);
PAINT WHITE (4475 275);
FORCENOTE
0: NON-LEGACY. DMI3 IS NOT INITIALIZED
(4475 450) 0;
DISPLAY LEFT (4475 450);
DISPLAY 1.021277 (4475 450);
PAINT WHITE (4475 450);
FORCENOTE
SERVICE PROCESSOR BOOT MODE
(4450 850) 0;
DISPLAY LEFT (4450 850);
DISPLAY 1.021277 (4450 850);
PAINT WHITE (4450 850);
FORCENOTE
NON-LEGACY CPUS = 01 OR 10 OR 11
(4475 975) 0;
DISPLAY LEFT (4475 975);
DISPLAY 1.021277 (4475 975);
PAINT WHITE (4475 975);
FORCENOTE
0: CPU IS NOT A TXT AGENT
(4475 1675) 0;
DISPLAY LEFT (4475 1675);
DISPLAY 1.021277 (4475 1675);
PAINT WHITE (4475 1675);
FORCENOTE
TXT AGENT (DRIVES TXT TRANSACTIONS)
(4450 1800) 0;
DISPLAY LEFT (4450 1800);
DISPLAY 1.021277 (4450 1800);
PAINT WHITE (4450 1800);
FORCENOTE
1: SAFE MODE BOOT ENABLED
(4475 1975) 0;
DISPLAY LEFT (4475 1975);
DISPLAY 1.021277 (4475 1975);
PAINT WHITE (4475 1975);
FORCENOTE
SAFE MODE BOOT (DISABLES CLOCK GATING)
(4450 2050) 0;
DISPLAY LEFT (4450 2050);
DISPLAY 1.021277 (4450 2050);
PAINT WHITE (4450 2050);
FORCENOTE
1-2    DISABLE BIST
(4500 4025) 0;
DISPLAY LEFT (4500 4025);
DISPLAY 0.808511 (4500 4025);
PAINT YELLOW (4500 4025);
FORCENOTE
DMIMODE_OVERRIDE
(2225 525) 0;
DISPLAY LEFT (2225 525);
DISPLAY 1.021277 (2225 525);
PAINT WHITE (2225 525);
FORCENOTE
20211201 CHANGE TXT,BIST TO ENABLE
(3175 -1500) 0;
DISPLAY LEFT (3175 -1500);
DISPLAY 1.063830 (3175 -1500);
PAINT WHITE (3175 -1500);
FORCENOTE
DESCRIPTION
(5125 2475) 0;
DISPLAY LEFT (5125 2475);
DISPLAY 1.021277 (5125 2475);
PAINT WHITE (5125 2475);
FORCENOTE
PU/PD
(3150 2425) 0;
DISPLAY LEFT (3150 2425);
DISPLAY 1.021277 (3150 2425);
PAINT WHITE (3150 2425);
FORCENOTE
2-3    ENABLE BIST (DEFAULT)
(4500 4150) 0;
DISPLAY LEFT (4500 4150);
DISPLAY 0.808511 (4500 4150);
PAINT YELLOW (4500 4150);
FORCENOTE
CPU0
(3650 2500) 0;
DISPLAY LEFT (3650 2500);
DISPLAY 1.021277 (3650 2500);
PAINT WHITE (3650 2500);
FORCENOTE
1
(3750 2250) 0;
DISPLAY LEFT (3750 2250);
DISPLAY 1.021277 (3750 2250);
PAINT WHITE (3750 2250);
FORCENOTE
0
(3750 2000) 0;
DISPLAY LEFT (3750 2000);
DISPLAY 1.021277 (3750 2000);
PAINT WHITE (3750 2000);
FORCENOTE
20220725 DEPOP R288
(3050 -775) 0;
DISPLAY LEFT (3050 -775);
DISPLAY 1.063830 (3050 -775);
PAINT WHITE (3050 -775);
FORCENOTE
1-2     DISABLE
(2550 -375) 0;
DISPLAY LEFT (2550 -375);
DISPLAY 0.808511 (2550 -375);
PAINT YELLOW (2550 -375);
FORCENOTE
2-3     ENABLE (DEFAULT)
(2550 -250) 0;
DISPLAY LEFT (2550 -250);
DISPLAY 0.808511 (2550 -250);
PAINT YELLOW (2550 -250);
FORCENOTE
CPU1 HW STRAPS
(3075 25) 0;
DISPLAY LEFT (3075 25);
DISPLAY 1.595745 (3075 25);
PAINT SKYBLUE (3075 25);
FORCENOTE
PD
(3275 300) 0;
DISPLAY LEFT (3275 300);
DISPLAY 1.021277 (3275 300);
PAINT WHITE (3275 300);
FORCENOTE
PU
(3275 525) 0;
DISPLAY LEFT (3275 525);
DISPLAY 1.021277 (3275 525);
PAINT WHITE (3275 525);
FORCENOTE
PD
(3275 775) 0;
DISPLAY LEFT (3275 775);
DISPLAY 1.021277 (3275 775);
PAINT WHITE (3275 775);
FORCENOTE
PD
(3275 1025) 0;
DISPLAY LEFT (3275 1025);
DISPLAY 1.021277 (3275 1025);
PAINT WHITE (3275 1025);
FORCENOTE
PD
(3275 1250) 0;
DISPLAY LEFT (3275 1250);
DISPLAY 1.021277 (3275 1250);
PAINT WHITE (3275 1250);
FORCENOTE
PU
(3275 1500) 0;
DISPLAY LEFT (3275 1500);
DISPLAY 1.021277 (3275 1500);
PAINT WHITE (3275 1500);
FORCENOTE
PD
(3275 1750) 0;
DISPLAY LEFT (3275 1750);
DISPLAY 1.021277 (3275 1750);
PAINT WHITE (3275 1750);
FORCENOTE
PD
(3275 2000) 0;
DISPLAY LEFT (3275 2000);
DISPLAY 1.021277 (3275 2000);
PAINT WHITE (3275 2000);
FORCENOTE
SPR PIN NAME
(2225 2475) 0;
DISPLAY LEFT (2225 2475);
DISPLAY 1.021277 (2225 2475);
PAINT WHITE (2225 2475);
FORCENOTE
20220725 DEPOP R292
(3125 3525) 0;
DISPLAY LEFT (3125 3525);
DISPLAY 1.063830 (3125 3525);
PAINT WHITE (3125 3525);
FORCENOTE
INTERNAL
(3150 2500) 0;
DISPLAY LEFT (3150 2500);
DISPLAY 1.021277 (3150 2500);
PAINT WHITE (3150 2500);
FORCENOTE
PU
(3275 2250) 0;
DISPLAY LEFT (3275 2250);
DISPLAY 1.021277 (3275 2250);
PAINT WHITE (3275 2250);
FORCENOTE
CPU1
(4075 2500) 0;
DISPLAY LEFT (4075 2500);
DISPLAY 1.021277 (4075 2500);
PAINT WHITE (4075 2500);
FORCENOTE
(DEFAULT)
(4000 2425) 0;
DISPLAY LEFT (4000 2425);
DISPLAY 1.021277 (4000 2425);
PAINT WHITE (4000 2425);
FORCENOTE
(DEFAULT)
(3575 2425) 0;
DISPLAY LEFT (3575 2425);
DISPLAY 1.021277 (3575 2425);
PAINT WHITE (3575 2425);
QUIT
